G04 ================== begin FILE IDENTIFICATION RECORD ==================*
G04 Layout Name:  16368-sb.brd*
G04 Film Name:    SE_REF_L1*
G04 File Format:  Gerber RS274X*
G04 File Origin:  Cadence Allegro 16.5-S056*
G04 Origin Date:  Tue Feb 07 09:07:45 2017*
G04 *
G04 Layer:  BOARD GEOMETRY/SE_REF_L1_TBL*
G04 Layer:  BOARD GEOMETRY/SE_REF_L1_TOP*
G04 Layer:  BOARD GEOMETRY/PANEL_OUTLINE*
G04 *
G04 Offset:    (0.00 0.00)*
G04 Mirror:    No*
G04 Mode:      Positive*
G04 Rotation:  0*
G04 FullContactRelief:  No*
G04 UndefLineWidth:     6.00*
G04 ================== end FILE IDENTIFICATION RECORD ====================*
%FSLAX35Y35*MOIN*%
%IR0*IPPOS*OFA0.00000B0.00000*MIA0B0*SFA1.00000B1.00000*%
%ADD10C,.02*%
%ADD11C,.006*%
%ADD12C,.007*%
G75*
%LPD*%
G75*
G54D10*
G01X597544Y585326D02*
X1315044D01*
G01X597544Y654626D02*
Y585326D01*
G01Y654626D02*
X1315044D01*
G01X597544Y619976D02*
X1315044D01*
G01X772544Y654626D02*
Y585326D01*
G01X1000044Y654626D02*
Y585326D01*
G01X1105044Y654626D02*
Y585326D01*
G01X1315044Y654626D02*
Y585326D01*
G54D11*
G01X6250Y-52485D02*
Y-69985D01*
G01X1228Y-52485D02*
X11272D01*
G01X20038Y-69985D02*
Y-52485D01*
G01Y-60943D02*
X21130Y-59485D01*
X22222Y-58610D01*
X23968Y-58319D01*
X25278Y-58610D01*
X26807Y-59777D01*
X27462Y-61527D01*
Y-69985D01*
G01X41250Y-58319D02*
Y-69985D01*
G01Y-53652D02*
X40813Y-53360D01*
Y-52777D01*
X41250Y-52485D01*
X41687Y-52777D01*
Y-53360D01*
X41250Y-53652D01*
G01X55475Y-67944D02*
X56567Y-69110D01*
X58095Y-69985D01*
X59405D01*
X60715Y-69402D01*
X61588Y-68527D01*
X62025Y-67361D01*
X61807Y-65610D01*
X60933Y-64735D01*
X57003Y-62985D01*
X56130Y-60943D01*
X56567Y-59485D01*
X57440Y-58610D01*
X58750Y-58319D01*
X60060Y-58610D01*
X61370Y-59485D01*
G01X90693Y-74360D02*
X92222Y-75527D01*
X93968Y-75818D01*
X95496Y-75527D01*
X96807Y-74069D01*
X97680Y-72027D01*
Y-58319D01*
G01Y-60652D02*
X96807Y-59485D01*
X95496Y-58610D01*
X93968Y-58319D01*
X92222Y-58902D01*
X91130Y-60068D01*
X90256Y-62110D01*
X89820Y-64152D01*
X90038Y-65902D01*
X90912Y-67944D01*
X92222Y-69402D01*
X93968Y-69985D01*
X95278Y-69693D01*
X96807Y-68527D01*
X97680Y-67361D01*
G01X107975Y-62110D02*
X114962D01*
X114307Y-60068D01*
X113215Y-58902D01*
X111687Y-58319D01*
X110158Y-58610D01*
X108848Y-59485D01*
X107975Y-61527D01*
X107538Y-63277D01*
Y-65027D01*
X107975Y-66777D01*
X109067Y-68527D01*
X110377Y-69693D01*
X111905Y-69985D01*
X113433Y-69402D01*
X114962Y-67652D01*
G01X125693Y-69985D02*
Y-58319D01*
G01Y-60652D02*
X126785Y-59485D01*
X127877Y-58610D01*
X129405Y-58319D01*
X130496Y-58610D01*
X131807Y-59485D01*
G01X142320Y-69985D02*
Y-52485D01*
G01Y-61235D02*
X143412Y-59485D01*
X144722Y-58610D01*
X146032Y-58319D01*
X147996Y-58902D01*
X149307Y-60068D01*
X150180Y-62110D01*
Y-64443D01*
X149743Y-66777D01*
X148870Y-68527D01*
X147342Y-69693D01*
X146032Y-69985D01*
X144722Y-69693D01*
X143412Y-68819D01*
X142320Y-67361D01*
G01X160475Y-62110D02*
X167462D01*
X166807Y-60068D01*
X165715Y-58902D01*
X164187Y-58319D01*
X162658Y-58610D01*
X161348Y-59485D01*
X160475Y-61527D01*
X160038Y-63277D01*
Y-65027D01*
X160475Y-66777D01*
X161567Y-68527D01*
X162877Y-69693D01*
X164405Y-69985D01*
X165933Y-69402D01*
X167462Y-67652D01*
G01X178193Y-69985D02*
Y-58319D01*
G01Y-60652D02*
X179285Y-59485D01*
X180377Y-58610D01*
X181905Y-58319D01*
X182996Y-58610D01*
X184307Y-59485D01*
G01X216250Y-58319D02*
Y-69985D01*
G01Y-53652D02*
X215813Y-53360D01*
Y-52777D01*
X216250Y-52485D01*
X216687Y-52777D01*
Y-53360D01*
X216250Y-53652D01*
G01X230475Y-67944D02*
X231567Y-69110D01*
X233095Y-69985D01*
X234405D01*
X235715Y-69402D01*
X236588Y-68527D01*
X237025Y-67361D01*
X236807Y-65610D01*
X235933Y-64735D01*
X232003Y-62985D01*
X231130Y-60943D01*
X231567Y-59485D01*
X232440Y-58610D01*
X233750Y-58319D01*
X235060Y-58610D01*
X236370Y-59485D01*
G01X265256Y-74360D02*
X266785Y-75527D01*
X268095Y-75818D01*
X269842Y-75235D01*
X271152Y-73777D01*
X271807Y-71151D01*
Y-58319D01*
G01Y-53652D02*
X271370Y-53360D01*
Y-52777D01*
X271807Y-52485D01*
X272243Y-52777D01*
Y-53360D01*
X271807Y-53652D01*
G01X282538Y-58319D02*
Y-66485D01*
X283412Y-68527D01*
X284722Y-69693D01*
X286250Y-69985D01*
X287778Y-69693D01*
X289088Y-68527D01*
X289962Y-66485D01*
G01Y-69985D02*
Y-58319D01*
G01X300475Y-67944D02*
X301567Y-69110D01*
X303095Y-69985D01*
X304405D01*
X305715Y-69402D01*
X306588Y-68527D01*
X307025Y-67361D01*
X306807Y-65610D01*
X305933Y-64735D01*
X302003Y-62985D01*
X301130Y-60943D01*
X301567Y-59485D01*
X302440Y-58610D01*
X303750Y-58319D01*
X305060Y-58610D01*
X306370Y-59485D01*
G01X321250Y-52485D02*
Y-69985D01*
G01X318193Y-58319D02*
X324307D01*
G01X354940Y-69985D02*
Y-55110D01*
X355377Y-53652D01*
X356250Y-52777D01*
X357560Y-52485D01*
X358870Y-53068D01*
X359525Y-54527D01*
G01X356905Y-59485D02*
X352538D01*
G01X373750Y-69985D02*
X372440Y-69693D01*
X371130Y-68527D01*
X370256Y-66485D01*
X369820Y-64152D01*
X370256Y-61818D01*
X371130Y-59777D01*
X372440Y-58610D01*
X373750Y-58319D01*
X375060Y-58610D01*
X376370Y-59777D01*
X377243Y-61818D01*
X377462Y-64152D01*
X377243Y-66485D01*
X376370Y-68527D01*
X375060Y-69693D01*
X373750Y-69985D01*
G01X388193D02*
Y-58319D01*
G01Y-60652D02*
X389285Y-59485D01*
X390377Y-58610D01*
X391905Y-58319D01*
X392996Y-58610D01*
X394307Y-59485D01*
G01X421665Y-75235D02*
X422975Y-75818D01*
X424722Y-75235D01*
X425813Y-74069D01*
X426687Y-72610D01*
X427996Y-67944D01*
X430835Y-58319D01*
G01X423848D02*
X427996Y-67944D01*
G01X443750Y-69985D02*
X442440Y-69693D01*
X441130Y-68527D01*
X440256Y-66485D01*
X439820Y-64152D01*
X440256Y-61818D01*
X441130Y-59777D01*
X442440Y-58610D01*
X443750Y-58319D01*
X445060Y-58610D01*
X446370Y-59777D01*
X447243Y-61818D01*
X447462Y-64152D01*
X447243Y-66485D01*
X446370Y-68527D01*
X445060Y-69693D01*
X443750Y-69985D01*
G01X457538Y-58319D02*
Y-66485D01*
X458412Y-68527D01*
X459722Y-69693D01*
X461250Y-69985D01*
X462778Y-69693D01*
X464088Y-68527D01*
X464962Y-66485D01*
G01Y-69985D02*
Y-58319D01*
G01X475693Y-69985D02*
Y-58319D01*
G01Y-60652D02*
X476785Y-59485D01*
X477877Y-58610D01*
X479405Y-58319D01*
X480496Y-58610D01*
X481807Y-59485D01*
G01X510693Y-69985D02*
Y-58319D01*
G01Y-60652D02*
X511785Y-59485D01*
X512877Y-58610D01*
X514405Y-58319D01*
X515496Y-58610D01*
X516807Y-59485D01*
G01X527975Y-62110D02*
X534962D01*
X534307Y-60068D01*
X533215Y-58902D01*
X531687Y-58319D01*
X530158Y-58610D01*
X528848Y-59485D01*
X527975Y-61527D01*
X527538Y-63277D01*
Y-65027D01*
X527975Y-66777D01*
X529067Y-68527D01*
X530377Y-69693D01*
X531905Y-69985D01*
X533433Y-69402D01*
X534962Y-67652D01*
G01X547440Y-69985D02*
Y-55110D01*
X547877Y-53652D01*
X548750Y-52777D01*
X550060Y-52485D01*
X551370Y-53068D01*
X552025Y-54527D01*
G01X549405Y-59485D02*
X545038D01*
G01X562975Y-62110D02*
X569962D01*
X569307Y-60068D01*
X568215Y-58902D01*
X566687Y-58319D01*
X565158Y-58610D01*
X563848Y-59485D01*
X562975Y-61527D01*
X562538Y-63277D01*
Y-65027D01*
X562975Y-66777D01*
X564067Y-68527D01*
X565377Y-69693D01*
X566905Y-69985D01*
X568433Y-69402D01*
X569962Y-67652D01*
G01X580693Y-69985D02*
Y-58319D01*
G01Y-60652D02*
X581785Y-59485D01*
X582877Y-58610D01*
X584405Y-58319D01*
X585496Y-58610D01*
X586807Y-59485D01*
G01X597975Y-62110D02*
X604962D01*
X604307Y-60068D01*
X603215Y-58902D01*
X601687Y-58319D01*
X600158Y-58610D01*
X598848Y-59485D01*
X597975Y-61527D01*
X597538Y-63277D01*
Y-65027D01*
X597975Y-66777D01*
X599067Y-68527D01*
X600377Y-69693D01*
X601905Y-69985D01*
X603433Y-69402D01*
X604962Y-67652D01*
G01X615038Y-69985D02*
Y-58319D01*
G01Y-61235D02*
X615912Y-59777D01*
X617222Y-58610D01*
X618968Y-58319D01*
X620496Y-58610D01*
X621807Y-59777D01*
X622462Y-61818D01*
Y-69985D01*
G01X639743Y-59777D02*
X638215Y-58610D01*
X636905Y-58319D01*
X635158Y-58902D01*
X633848Y-60068D01*
X632975Y-62110D01*
X632756Y-64152D01*
X632975Y-66194D01*
X633848Y-67944D01*
X635158Y-69402D01*
X636905Y-69985D01*
X638433Y-69402D01*
X639743Y-68235D01*
G01X650475Y-62110D02*
X657462D01*
X656807Y-60068D01*
X655715Y-58902D01*
X654187Y-58319D01*
X652658Y-58610D01*
X651348Y-59485D01*
X650475Y-61527D01*
X650038Y-63277D01*
Y-65027D01*
X650475Y-66777D01*
X651567Y-68527D01*
X652877Y-69693D01*
X654405Y-69985D01*
X655933Y-69402D01*
X657462Y-67652D01*
G01X688750Y-52485D02*
Y-69985D01*
G01X685693Y-58319D02*
X691807D01*
G01X706250Y-69985D02*
X704940Y-69693D01*
X703630Y-68527D01*
X702756Y-66485D01*
X702320Y-64152D01*
X702756Y-61818D01*
X703630Y-59777D01*
X704940Y-58610D01*
X706250Y-58319D01*
X707560Y-58610D01*
X708870Y-59777D01*
X709743Y-61818D01*
X709962Y-64152D01*
X709743Y-66485D01*
X708870Y-68527D01*
X707560Y-69693D01*
X706250Y-69985D01*
G01X739940D02*
Y-55110D01*
X740377Y-53652D01*
X741250Y-52777D01*
X742560Y-52485D01*
X743870Y-53068D01*
X744525Y-54527D01*
G01X741905Y-59485D02*
X737538D01*
G01X758750Y-58319D02*
Y-69985D01*
G01Y-53652D02*
X758313Y-53360D01*
Y-52777D01*
X758750Y-52485D01*
X759187Y-52777D01*
Y-53360D01*
X758750Y-53652D01*
G01X772538Y-69985D02*
Y-58319D01*
G01Y-61235D02*
X773412Y-59777D01*
X774722Y-58610D01*
X776468Y-58319D01*
X777996Y-58610D01*
X779307Y-59777D01*
X779962Y-61818D01*
Y-69985D01*
G01X797680Y-52485D02*
Y-69985D01*
G01Y-67361D02*
X796807Y-68819D01*
X795496Y-69693D01*
X793968Y-69985D01*
X792222Y-69402D01*
X790912Y-67944D01*
X790038Y-66194D01*
X789820Y-64152D01*
X790038Y-62110D01*
X790912Y-60360D01*
X792222Y-58902D01*
X793968Y-58319D01*
X795496Y-58610D01*
X796588Y-59194D01*
X797680Y-60360D01*
G01X828750Y-52485D02*
Y-69985D01*
G01X825693Y-58319D02*
X831807D01*
G01X842538Y-69985D02*
Y-52485D01*
G01Y-60943D02*
X843630Y-59485D01*
X844722Y-58610D01*
X846468Y-58319D01*
X847778Y-58610D01*
X849307Y-59777D01*
X849962Y-61527D01*
Y-69985D01*
G01X860475Y-62110D02*
X867462D01*
X866807Y-60068D01*
X865715Y-58902D01*
X864187Y-58319D01*
X862658Y-58610D01*
X861348Y-59485D01*
X860475Y-61527D01*
X860038Y-63277D01*
Y-65027D01*
X860475Y-66777D01*
X861567Y-68527D01*
X862877Y-69693D01*
X864405Y-69985D01*
X865933Y-69402D01*
X867462Y-67652D01*
G01X894165D02*
X895912Y-69110D01*
X897877Y-69985D01*
X899623D01*
X901370Y-69110D01*
X902680Y-67652D01*
X903335Y-65610D01*
X902898Y-63569D01*
X901807Y-61818D01*
X899842Y-60652D01*
X897222Y-60068D01*
X895693Y-58902D01*
X895038Y-56860D01*
X895475Y-54818D01*
X896567Y-53360D01*
X898095Y-52485D01*
X899623D01*
X901152Y-53068D01*
X902462Y-54527D01*
G01X920617Y-69985D02*
X911883D01*
Y-52485D01*
X920617D01*
G01X917123Y-60943D02*
X911883D01*
G01X951250Y-58319D02*
Y-69985D01*
G01Y-53652D02*
X950813Y-53360D01*
Y-52777D01*
X951250Y-52485D01*
X951687Y-52777D01*
Y-53360D01*
X951250Y-53652D01*
G01X962200Y-69985D02*
Y-58319D01*
G01Y-61527D02*
X962855Y-60068D01*
X963947Y-58902D01*
X965475Y-58319D01*
X967003Y-58902D01*
X968095Y-60068D01*
X968750Y-61527D01*
Y-69985D01*
G01Y-61527D02*
X969405Y-60068D01*
X970496Y-58902D01*
X972025Y-58319D01*
X973553Y-58902D01*
X974645Y-60068D01*
X975300Y-61818D01*
Y-69985D01*
G01X982320Y-75818D02*
Y-58319D01*
G01Y-60943D02*
X983412Y-59485D01*
X984503Y-58610D01*
X986250Y-58319D01*
X987778Y-58610D01*
X989307Y-60068D01*
X989962Y-62110D01*
X990180Y-64152D01*
X989962Y-66194D01*
X989307Y-68235D01*
X987996Y-69402D01*
X986250Y-69985D01*
X984722Y-69693D01*
X983193Y-68819D01*
X982320Y-67652D01*
G01X1000475Y-62110D02*
X1007462D01*
X1006807Y-60068D01*
X1005715Y-58902D01*
X1004187Y-58319D01*
X1002658Y-58610D01*
X1001348Y-59485D01*
X1000475Y-61527D01*
X1000038Y-63277D01*
Y-65027D01*
X1000475Y-66777D01*
X1001567Y-68527D01*
X1002877Y-69693D01*
X1004405Y-69985D01*
X1005933Y-69402D01*
X1007462Y-67652D01*
G01X1025180Y-52485D02*
Y-69985D01*
G01Y-67361D02*
X1024307Y-68819D01*
X1022996Y-69693D01*
X1021468Y-69985D01*
X1019722Y-69402D01*
X1018412Y-67944D01*
X1017538Y-66194D01*
X1017320Y-64152D01*
X1017538Y-62110D01*
X1018412Y-60360D01*
X1019722Y-58902D01*
X1021468Y-58319D01*
X1022996Y-58610D01*
X1024088Y-59194D01*
X1025180Y-60360D01*
G01X1042680Y-69985D02*
Y-58319D01*
G01Y-60360D02*
X1041807Y-59194D01*
X1040496Y-58610D01*
X1038968Y-58319D01*
X1037440Y-58902D01*
X1036130Y-60068D01*
X1035256Y-61818D01*
X1034820Y-64152D01*
X1035256Y-66485D01*
X1036130Y-68235D01*
X1037440Y-69402D01*
X1038968Y-69985D01*
X1040496Y-69693D01*
X1041807Y-68819D01*
X1042680Y-67652D01*
G01X1052538Y-69985D02*
Y-58319D01*
G01Y-61235D02*
X1053412Y-59777D01*
X1054722Y-58610D01*
X1056468Y-58319D01*
X1057996Y-58610D01*
X1059307Y-59777D01*
X1059962Y-61818D01*
Y-69985D01*
G01X1077243Y-59777D02*
X1075715Y-58610D01*
X1074405Y-58319D01*
X1072658Y-58902D01*
X1071348Y-60068D01*
X1070475Y-62110D01*
X1070256Y-64152D01*
X1070475Y-66194D01*
X1071348Y-67944D01*
X1072658Y-69402D01*
X1074405Y-69985D01*
X1075933Y-69402D01*
X1077243Y-68235D01*
G01X1087975Y-62110D02*
X1094962D01*
X1094307Y-60068D01*
X1093215Y-58902D01*
X1091687Y-58319D01*
X1090158Y-58610D01*
X1088848Y-59485D01*
X1087975Y-61527D01*
X1087538Y-63277D01*
Y-65027D01*
X1087975Y-66777D01*
X1089067Y-68527D01*
X1090377Y-69693D01*
X1091905Y-69985D01*
X1093433Y-69402D01*
X1094962Y-67652D01*
G01X1126250Y-52485D02*
Y-69985D01*
G01X1123193Y-58319D02*
X1129307D01*
G01X1140693Y-69985D02*
Y-58319D01*
G01Y-60652D02*
X1141785Y-59485D01*
X1142877Y-58610D01*
X1144405Y-58319D01*
X1145496Y-58610D01*
X1146807Y-59485D01*
G01X1165180Y-69985D02*
Y-58319D01*
G01Y-60360D02*
X1164307Y-59194D01*
X1162996Y-58610D01*
X1161468Y-58319D01*
X1159940Y-58902D01*
X1158630Y-60068D01*
X1157756Y-61818D01*
X1157320Y-64152D01*
X1157756Y-66485D01*
X1158630Y-68235D01*
X1159940Y-69402D01*
X1161468Y-69985D01*
X1162996Y-69693D01*
X1164307Y-68819D01*
X1165180Y-67652D01*
G01X1182243Y-59777D02*
X1180715Y-58610D01*
X1179405Y-58319D01*
X1177658Y-58902D01*
X1176348Y-60068D01*
X1175475Y-62110D01*
X1175256Y-64152D01*
X1175475Y-66194D01*
X1176348Y-67944D01*
X1177658Y-69402D01*
X1179405Y-69985D01*
X1180933Y-69402D01*
X1182243Y-68235D01*
G01X1192975Y-62110D02*
X1199962D01*
X1199307Y-60068D01*
X1198215Y-58902D01*
X1196687Y-58319D01*
X1195158Y-58610D01*
X1193848Y-59485D01*
X1192975Y-61527D01*
X1192538Y-63277D01*
Y-65027D01*
X1192975Y-66777D01*
X1194067Y-68527D01*
X1195377Y-69693D01*
X1196905Y-69985D01*
X1198433Y-69402D01*
X1199962Y-67652D01*
G01X1210475Y-67944D02*
X1211567Y-69110D01*
X1213095Y-69985D01*
X1214405D01*
X1215715Y-69402D01*
X1216588Y-68527D01*
X1217025Y-67361D01*
X1216807Y-65610D01*
X1215933Y-64735D01*
X1212003Y-62985D01*
X1211130Y-60943D01*
X1211567Y-59485D01*
X1212440Y-58610D01*
X1213750Y-58319D01*
X1215060Y-58610D01*
X1216370Y-59485D01*
G01X1248750Y-58319D02*
Y-69985D01*
G01Y-53652D02*
X1248313Y-53360D01*
Y-52777D01*
X1248750Y-52485D01*
X1249187Y-52777D01*
Y-53360D01*
X1248750Y-53652D01*
G01X1262538Y-69985D02*
Y-58319D01*
G01Y-61235D02*
X1263412Y-59777D01*
X1264722Y-58610D01*
X1266468Y-58319D01*
X1267996Y-58610D01*
X1269307Y-59777D01*
X1269962Y-61818D01*
Y-69985D01*
G01X1301250D02*
Y-52485D01*
G01X1322680Y-69985D02*
Y-58319D01*
G01Y-60360D02*
X1321807Y-59194D01*
X1320496Y-58610D01*
X1318968Y-58319D01*
X1317440Y-58902D01*
X1316130Y-60068D01*
X1315256Y-61818D01*
X1314820Y-64152D01*
X1315256Y-66485D01*
X1316130Y-68235D01*
X1317440Y-69402D01*
X1318968Y-69985D01*
X1320496Y-69693D01*
X1321807Y-68819D01*
X1322680Y-67652D01*
G01X1331665Y-75235D02*
X1332975Y-75818D01*
X1334722Y-75235D01*
X1335813Y-74069D01*
X1336687Y-72610D01*
X1337996Y-67944D01*
X1340835Y-58319D01*
G01X1333848D02*
X1337996Y-67944D01*
G01X1350475Y-62110D02*
X1357462D01*
X1356807Y-60068D01*
X1355715Y-58902D01*
X1354187Y-58319D01*
X1352658Y-58610D01*
X1351348Y-59485D01*
X1350475Y-61527D01*
X1350038Y-63277D01*
Y-65027D01*
X1350475Y-66777D01*
X1351567Y-68527D01*
X1352877Y-69693D01*
X1354405Y-69985D01*
X1355933Y-69402D01*
X1357462Y-67652D01*
G01X1368193Y-69985D02*
Y-58319D01*
G01Y-60652D02*
X1369285Y-59485D01*
X1370377Y-58610D01*
X1371905Y-58319D01*
X1372996Y-58610D01*
X1374307Y-59485D01*
G01X1401883Y-52485D02*
Y-69985D01*
X1410617D01*
G01X1423750D02*
Y-52485D01*
X1421130Y-55985D01*
G01Y-69985D02*
X1426370D01*
G01X1441250Y-70568D02*
X1440813Y-70277D01*
Y-69693D01*
X1441250Y-69402D01*
X1441687Y-69693D01*
Y-70277D01*
X1441250Y-70568D01*
G01X599509Y666709D02*
X601256Y665251D01*
X603221Y664376D01*
X604967D01*
X606714Y665251D01*
X608024Y666709D01*
X608679Y668751D01*
X608242Y670792D01*
X607151Y672543D01*
X605186Y673709D01*
X602566Y674293D01*
X601037Y675459D01*
X600382Y677501D01*
X600819Y679543D01*
X601911Y681001D01*
X603439Y681876D01*
X604967D01*
X606496Y681293D01*
X607806Y679834D01*
G01X625961Y664376D02*
X617227D01*
Y681876D01*
X625961D01*
G01X622467Y673418D02*
X617227D01*
G01X653974Y681876D02*
X659214D01*
G01X656594D02*
Y664376D01*
G01X653974D02*
X659214D01*
G01X668417D02*
Y681876D01*
X674094Y667293D01*
X679771Y681876D01*
Y664376D01*
G01X687227D02*
Y681876D01*
X692467D01*
X694214Y681001D01*
X695524Y678959D01*
X695961Y676626D01*
X695524Y674293D01*
X694432Y672543D01*
X692467Y671667D01*
X687227D01*
G01X713461Y664376D02*
X704727D01*
Y681876D01*
X713461D01*
G01X709967Y673418D02*
X704727D01*
G01X721791Y664376D02*
Y681876D01*
X726157D01*
X727904Y681001D01*
X729214Y679834D01*
X730306Y678085D01*
X731179Y676042D01*
X731397Y673126D01*
X731179Y670209D01*
X730306Y668167D01*
X729214Y666417D01*
X727904Y665251D01*
X726157Y664376D01*
X721791D01*
G01X738635D02*
X744094Y681876D01*
X749553Y664376D01*
G01X747587Y670501D02*
X740600D01*
G01X756572Y664376D02*
Y681876D01*
X766616Y664376D01*
Y681876D01*
G01X783897Y680417D02*
X782587Y681293D01*
X781059Y681876D01*
X779312D01*
X777347Y681001D01*
X775819Y679543D01*
X774727Y677792D01*
X773854Y674876D01*
X773635Y672251D01*
X774072Y669626D01*
X774727Y667876D01*
X776037Y666126D01*
X777566Y664959D01*
X779094Y664376D01*
X780622D01*
X782151Y664959D01*
X783461Y665834D01*
X784553Y667000D01*
G01X800961Y664376D02*
X792227D01*
Y681876D01*
X800961D01*
G01X797467Y673418D02*
X792227D01*
G01X831594Y681876D02*
Y664376D01*
G01X826572Y681876D02*
X836616D01*
G01X843635Y664376D02*
X849094Y681876D01*
X854553Y664376D01*
G01X852587Y670501D02*
X845600D01*
G01X868340Y673709D02*
X869214Y674584D01*
X869869Y676042D01*
X870306Y678085D01*
X869869Y679834D01*
X868996Y681001D01*
X867467Y681876D01*
X861572D01*
Y664376D01*
X868777D01*
X870306Y665542D01*
X871179Y667293D01*
X871616Y669334D01*
X871179Y671376D01*
X869869Y673126D01*
X868340Y673709D01*
X861572D01*
G01X879727Y681876D02*
Y664376D01*
X888461D01*
G01X905961D02*
X897227D01*
Y681876D01*
X905961D01*
G01X902467Y673418D02*
X897227D01*
G01X919094Y663793D02*
X918657Y664084D01*
Y664668D01*
X919094Y664959D01*
X919531Y664668D01*
Y664084D01*
X919094Y663793D01*
G01Y671667D02*
X918657Y671959D01*
Y672543D01*
X919094Y672834D01*
X919531Y672543D01*
Y671959D01*
X919094Y671667D01*
G01X949727Y681876D02*
Y664376D01*
X958461D01*
G01X971594D02*
Y681876D01*
X968974Y678376D01*
G01Y664376D02*
X974214D01*
G01X653991Y597700D02*
X655300Y596242D01*
X656829Y595368D01*
X658794Y595076D01*
X660759Y595659D01*
X662287Y596826D01*
X663379Y598867D01*
X663597Y601201D01*
X663161Y603534D01*
X662069Y604993D01*
X660540Y606159D01*
X659012Y606451D01*
X657484Y606159D01*
X655519Y604993D01*
X656174Y612576D01*
X662069D01*
G01X676294D02*
X674547Y611993D01*
X673237Y610534D01*
X672364Y608785D01*
X671709Y606451D01*
X671491Y603826D01*
X671709Y601201D01*
X672364Y598867D01*
X673237Y597117D01*
X674547Y595659D01*
X676294Y595076D01*
X678040Y595659D01*
X679351Y597117D01*
X680224Y598867D01*
X680879Y601201D01*
X681097Y603826D01*
X680879Y606451D01*
X680224Y608785D01*
X679351Y610534D01*
X678040Y611993D01*
X676294Y612576D01*
G01X693794Y594493D02*
X693357Y594784D01*
Y595368D01*
X693794Y595659D01*
X694231Y595368D01*
Y594784D01*
X693794Y594493D01*
G01X711294Y612576D02*
X709547Y611993D01*
X708237Y610534D01*
X707364Y608785D01*
X706709Y606451D01*
X706491Y603826D01*
X706709Y601201D01*
X707364Y598867D01*
X708237Y597117D01*
X709547Y595659D01*
X711294Y595076D01*
X713040Y595659D01*
X714351Y597117D01*
X715224Y598867D01*
X715879Y601201D01*
X716097Y603826D01*
X715879Y606451D01*
X715224Y608785D01*
X714351Y610534D01*
X713040Y611993D01*
X711294Y612576D01*
G01X621174Y647226D02*
X626414D01*
G01X623794D02*
Y629726D01*
G01X621174D02*
X626414D01*
G01X635617D02*
Y647226D01*
X641294Y632643D01*
X646971Y647226D01*
Y629726D01*
G01X654427D02*
Y647226D01*
X659667D01*
X661414Y646351D01*
X662724Y644309D01*
X663161Y641976D01*
X662724Y639643D01*
X661632Y637893D01*
X659667Y637017D01*
X654427D01*
G01X675202Y623893D02*
X673019Y626809D01*
X671927Y629726D01*
Y641392D01*
X673019Y644309D01*
X675202Y647226D01*
G01X693794Y629726D02*
X692047Y630018D01*
X690519Y631184D01*
X689209Y632934D01*
X688335Y634976D01*
X687899Y637309D01*
Y639643D01*
X688335Y641976D01*
X689209Y644018D01*
X690519Y645767D01*
X692047Y646934D01*
X693794Y647226D01*
X695540Y646934D01*
X697069Y645767D01*
X698379Y644018D01*
X699253Y641976D01*
X699689Y639643D01*
Y637309D01*
X699253Y634976D01*
X698379Y632934D01*
X697069Y631184D01*
X695540Y630018D01*
X693794Y629726D01*
G01X707582D02*
Y647226D01*
G01Y638768D02*
X708674Y640226D01*
X709766Y641101D01*
X711512Y641392D01*
X712822Y641101D01*
X714351Y639934D01*
X715006Y638184D01*
Y629726D01*
G01X722244D02*
Y641392D01*
G01Y638184D02*
X722899Y639643D01*
X723991Y640809D01*
X725519Y641392D01*
X727047Y640809D01*
X728139Y639643D01*
X728794Y638184D01*
Y629726D01*
G01Y638184D02*
X729449Y639643D01*
X730540Y640809D01*
X732069Y641392D01*
X733597Y640809D01*
X734689Y639643D01*
X735344Y637893D01*
Y629726D01*
G01X747386Y623893D02*
X749569Y626809D01*
X750661Y629726D01*
Y641392D01*
X749569Y644309D01*
X747386Y647226D01*
G01X792244D02*
X795300Y629726D01*
X798794Y647226D01*
X802287Y629726D01*
X805344Y647226D01*
G01X813674D02*
X818914D01*
G01X816294D02*
Y629726D01*
G01X813674D02*
X818914D01*
G01X828991D02*
Y647226D01*
X833357D01*
X835104Y646351D01*
X836414Y645184D01*
X837506Y643435D01*
X838379Y641392D01*
X838597Y638476D01*
X838379Y635559D01*
X837506Y633517D01*
X836414Y631767D01*
X835104Y630601D01*
X833357Y629726D01*
X828991D01*
G01X851294Y647226D02*
Y629726D01*
G01X846272Y647226D02*
X856316D01*
G01X864209Y629726D02*
Y647226D01*
G01X873379D02*
Y629726D01*
G01Y638476D02*
X864209D01*
G01X885202Y623893D02*
X883019Y626809D01*
X881927Y629726D01*
Y641392D01*
X883019Y644309D01*
X885202Y647226D01*
G01X897244Y629726D02*
Y641392D01*
G01Y638184D02*
X897899Y639643D01*
X898991Y640809D01*
X900519Y641392D01*
X902047Y640809D01*
X903139Y639643D01*
X903794Y638184D01*
Y629726D01*
G01Y638184D02*
X904449Y639643D01*
X905540Y640809D01*
X907069Y641392D01*
X908597Y640809D01*
X909689Y639643D01*
X910344Y637893D01*
Y629726D01*
G01X921294Y641392D02*
Y629726D01*
G01Y646059D02*
X920857Y646351D01*
Y646934D01*
X921294Y647226D01*
X921731Y646934D01*
Y646351D01*
X921294Y646059D01*
G01X938794Y629726D02*
Y647226D01*
G01X953019Y631767D02*
X954111Y630601D01*
X955639Y629726D01*
X956949D01*
X958259Y630309D01*
X959132Y631184D01*
X959569Y632350D01*
X959351Y634101D01*
X958477Y634976D01*
X954547Y636726D01*
X953674Y638768D01*
X954111Y640226D01*
X954984Y641101D01*
X956294Y641392D01*
X957604Y641101D01*
X958914Y640226D01*
G01X974886Y623893D02*
X977069Y626809D01*
X978161Y629726D01*
Y641392D01*
X977069Y644309D01*
X974886Y647226D01*
G01X868357Y595076D02*
X868794Y598867D01*
X869449Y602076D01*
X870322Y604993D01*
X871414Y608201D01*
X873161Y612576D01*
X864427D01*
G01X886294Y594493D02*
X885857Y594784D01*
Y595368D01*
X886294Y595659D01*
X886731Y595368D01*
Y594784D01*
X886294Y594493D01*
G01X903794Y612576D02*
X902047Y611993D01*
X900737Y610534D01*
X899864Y608785D01*
X899209Y606451D01*
X898991Y603826D01*
X899209Y601201D01*
X899864Y598867D01*
X900737Y597117D01*
X902047Y595659D01*
X903794Y595076D01*
X905540Y595659D01*
X906851Y597117D01*
X907724Y598867D01*
X908379Y601201D01*
X908597Y603826D01*
X908379Y606451D01*
X907724Y608785D01*
X906851Y610534D01*
X905540Y611993D01*
X903794Y612576D01*
G01X1026294Y647226D02*
Y629726D01*
G01X1021272Y647226D02*
X1031316D01*
G01X1043794Y629726D02*
Y637601D01*
X1039427Y647226D01*
G01X1048161D02*
X1043794Y637601D01*
G01X1056927Y629726D02*
Y647226D01*
X1062167D01*
X1063914Y646351D01*
X1065224Y644309D01*
X1065661Y641976D01*
X1065224Y639643D01*
X1064132Y637893D01*
X1062167Y637017D01*
X1056927D01*
G01X1083161Y629726D02*
X1074427D01*
Y647226D01*
X1083161D01*
G01X1079667Y638768D02*
X1074427D01*
G01X1039209Y597409D02*
X1040956Y595951D01*
X1042921Y595076D01*
X1044667D01*
X1046414Y595951D01*
X1047724Y597409D01*
X1048379Y599451D01*
X1047942Y601492D01*
X1046851Y603243D01*
X1044886Y604409D01*
X1042266Y604993D01*
X1040737Y606159D01*
X1040082Y608201D01*
X1040519Y610243D01*
X1041611Y611701D01*
X1043139Y612576D01*
X1044667D01*
X1046196Y611993D01*
X1047506Y610534D01*
G01X1065661Y595076D02*
X1056927D01*
Y612576D01*
X1065661D01*
G01X1062167Y604118D02*
X1056927D01*
G01X1126927Y629726D02*
Y647226D01*
X1132386D01*
X1134132Y646351D01*
X1135224Y645184D01*
X1135661Y642851D01*
X1135224Y640517D01*
X1133914Y639059D01*
X1132386Y638184D01*
X1126927D01*
G01X1132386D02*
X1135661Y629726D01*
G01X1145519Y637601D02*
X1152506D01*
X1151851Y639643D01*
X1150759Y640809D01*
X1149231Y641392D01*
X1147702Y641101D01*
X1146392Y640226D01*
X1145519Y638184D01*
X1145082Y636434D01*
Y634684D01*
X1145519Y632934D01*
X1146611Y631184D01*
X1147921Y630018D01*
X1149449Y629726D01*
X1150977Y630309D01*
X1152506Y632059D01*
G01X1164984Y629726D02*
Y644601D01*
X1165421Y646059D01*
X1166294Y646934D01*
X1167604Y647226D01*
X1168914Y646643D01*
X1169569Y645184D01*
G01X1166949Y640226D02*
X1162582D01*
G01X1183794Y629143D02*
X1183357Y629434D01*
Y630018D01*
X1183794Y630309D01*
X1184231Y630018D01*
Y629434D01*
X1183794Y629143D01*
G01X1214427Y629726D02*
Y647226D01*
X1219667D01*
X1221414Y646351D01*
X1222724Y644309D01*
X1223161Y641976D01*
X1222724Y639643D01*
X1221632Y637893D01*
X1219667Y637017D01*
X1214427D01*
G01X1236294Y629726D02*
Y647226D01*
G01X1257724Y629726D02*
Y641392D01*
G01Y639351D02*
X1256851Y640517D01*
X1255540Y641101D01*
X1254012Y641392D01*
X1252484Y640809D01*
X1251174Y639643D01*
X1250300Y637893D01*
X1249864Y635559D01*
X1250300Y633226D01*
X1251174Y631476D01*
X1252484Y630309D01*
X1254012Y629726D01*
X1255540Y630018D01*
X1256851Y630892D01*
X1257724Y632059D01*
G01X1267582Y629726D02*
Y641392D01*
G01Y638476D02*
X1268456Y639934D01*
X1269766Y641101D01*
X1271512Y641392D01*
X1273040Y641101D01*
X1274351Y639934D01*
X1275006Y637893D01*
Y629726D01*
G01X1285519Y637601D02*
X1292506D01*
X1291851Y639643D01*
X1290759Y640809D01*
X1289231Y641392D01*
X1287702Y641101D01*
X1286392Y640226D01*
X1285519Y638184D01*
X1285082Y636434D01*
Y634684D01*
X1285519Y632934D01*
X1286611Y631184D01*
X1287921Y630018D01*
X1289449Y629726D01*
X1290977Y630309D01*
X1292506Y632059D01*
G01X1196927Y612576D02*
Y595076D01*
X1205661D01*
G01X1214646Y609659D02*
X1215956Y611409D01*
X1217484Y612284D01*
X1219231Y612576D01*
X1221414Y611993D01*
X1222942Y610534D01*
X1223379Y608785D01*
X1223161Y607034D01*
X1222287Y605576D01*
X1217921Y602659D01*
X1215956Y600618D01*
X1214646Y597700D01*
X1214209Y595076D01*
X1223379D01*
G01X1406594Y606742D02*
Y595076D01*
G01Y611409D02*
X1406157Y611701D01*
Y612284D01*
X1406594Y612576D01*
X1407031Y612284D01*
Y611701D01*
X1406594Y611409D01*
G01X1420819Y597117D02*
X1421911Y595951D01*
X1423439Y595076D01*
X1424749D01*
X1426059Y595659D01*
X1426932Y596534D01*
X1427369Y597700D01*
X1427151Y599451D01*
X1426277Y600326D01*
X1422347Y602076D01*
X1421474Y604118D01*
X1421911Y605576D01*
X1422784Y606451D01*
X1424094Y606742D01*
X1425404Y606451D01*
X1426714Y605576D01*
G01X1454072Y595076D02*
Y612576D01*
X1464116Y595076D01*
Y612576D01*
G01X1476594Y595076D02*
X1474847Y595368D01*
X1473319Y596534D01*
X1472009Y598284D01*
X1471135Y600326D01*
X1470699Y602659D01*
Y604993D01*
X1471135Y607326D01*
X1472009Y609368D01*
X1473319Y611117D01*
X1474847Y612284D01*
X1476594Y612576D01*
X1478340Y612284D01*
X1479869Y611117D01*
X1481179Y609368D01*
X1482053Y607326D01*
X1482489Y604993D01*
Y602659D01*
X1482053Y600326D01*
X1481179Y598284D01*
X1479869Y596534D01*
X1478340Y595368D01*
X1476594Y595076D01*
G01X1494094Y612576D02*
Y595076D01*
G01X1489072Y612576D02*
X1499116D01*
G01X1525382Y606742D02*
Y598576D01*
X1526256Y596534D01*
X1527566Y595368D01*
X1529094Y595076D01*
X1530622Y595368D01*
X1531932Y596534D01*
X1532806Y598576D01*
G01Y595076D02*
Y606742D01*
G01X1543319Y597117D02*
X1544411Y595951D01*
X1545939Y595076D01*
X1547249D01*
X1548559Y595659D01*
X1549432Y596534D01*
X1549869Y597700D01*
X1549651Y599451D01*
X1548777Y600326D01*
X1544847Y602076D01*
X1543974Y604118D01*
X1544411Y605576D01*
X1545284Y606451D01*
X1546594Y606742D01*
X1547904Y606451D01*
X1549214Y605576D01*
G01X1560819Y602951D02*
X1567806D01*
X1567151Y604993D01*
X1566059Y606159D01*
X1564531Y606742D01*
X1563002Y606451D01*
X1561692Y605576D01*
X1560819Y603534D01*
X1560382Y601784D01*
Y600034D01*
X1560819Y598284D01*
X1561911Y596534D01*
X1563221Y595368D01*
X1564749Y595076D01*
X1566277Y595659D01*
X1567806Y597409D01*
G01X1585524Y612576D02*
Y595076D01*
G01Y597700D02*
X1584651Y596242D01*
X1583340Y595368D01*
X1581812Y595076D01*
X1580066Y595659D01*
X1578756Y597117D01*
X1577882Y598867D01*
X1577664Y600909D01*
X1577882Y602951D01*
X1578756Y604701D01*
X1580066Y606159D01*
X1581812Y606742D01*
X1583340Y606451D01*
X1584432Y605867D01*
X1585524Y604701D01*
G01X1616594Y606742D02*
Y595076D01*
G01Y611409D02*
X1616157Y611701D01*
Y612284D01*
X1616594Y612576D01*
X1617031Y612284D01*
Y611701D01*
X1616594Y611409D01*
G01X1630382Y595076D02*
Y606742D01*
G01Y603826D02*
X1631256Y605284D01*
X1632566Y606451D01*
X1634312Y606742D01*
X1635840Y606451D01*
X1637151Y605284D01*
X1637806Y603243D01*
Y595076D01*
G01X1669094Y612576D02*
Y595076D01*
G01X1666037Y606742D02*
X1672151D01*
G01X1682882Y595076D02*
Y612576D01*
G01Y604118D02*
X1683974Y605576D01*
X1685066Y606451D01*
X1686812Y606742D01*
X1688122Y606451D01*
X1689651Y605284D01*
X1690306Y603534D01*
Y595076D01*
G01X1704094Y606742D02*
Y595076D01*
G01Y611409D02*
X1703657Y611701D01*
Y612284D01*
X1704094Y612576D01*
X1704531Y612284D01*
Y611701D01*
X1704094Y611409D01*
G01X1718319Y597117D02*
X1719411Y595951D01*
X1720939Y595076D01*
X1722249D01*
X1723559Y595659D01*
X1724432Y596534D01*
X1724869Y597700D01*
X1724651Y599451D01*
X1723777Y600326D01*
X1719847Y602076D01*
X1718974Y604118D01*
X1719411Y605576D01*
X1720284Y606451D01*
X1721594Y606742D01*
X1722904Y606451D01*
X1724214Y605576D01*
G01X1756594Y595076D02*
Y612576D01*
G01X1778024Y595076D02*
Y606742D01*
G01Y604701D02*
X1777151Y605867D01*
X1775840Y606451D01*
X1774312Y606742D01*
X1772784Y606159D01*
X1771474Y604993D01*
X1770600Y603243D01*
X1770164Y600909D01*
X1770600Y598576D01*
X1771474Y596826D01*
X1772784Y595659D01*
X1774312Y595076D01*
X1775840Y595368D01*
X1777151Y596242D01*
X1778024Y597409D01*
G01X1787009Y589826D02*
X1788319Y589243D01*
X1790066Y589826D01*
X1791157Y590992D01*
X1792031Y592451D01*
X1793340Y597117D01*
X1796179Y606742D01*
G01X1789192D02*
X1793340Y597117D01*
G01X1805819Y602951D02*
X1812806D01*
X1812151Y604993D01*
X1811059Y606159D01*
X1809531Y606742D01*
X1808002Y606451D01*
X1806692Y605576D01*
X1805819Y603534D01*
X1805382Y601784D01*
Y600034D01*
X1805819Y598284D01*
X1806911Y596534D01*
X1808221Y595368D01*
X1809749Y595076D01*
X1811277Y595659D01*
X1812806Y597409D01*
G01X1823537Y595076D02*
Y606742D01*
G01Y604409D02*
X1824629Y605576D01*
X1825721Y606451D01*
X1827249Y606742D01*
X1828340Y606451D01*
X1829651Y605576D01*
G01X1406594Y572092D02*
Y560426D01*
G01Y576759D02*
X1406157Y577051D01*
Y577634D01*
X1406594Y577926D01*
X1407031Y577634D01*
Y577051D01*
X1406594Y576759D01*
G01X1420382Y560426D02*
Y572092D01*
G01Y569176D02*
X1421256Y570634D01*
X1422566Y571801D01*
X1424312Y572092D01*
X1425840Y571801D01*
X1427151Y570634D01*
X1427806Y568593D01*
Y560426D01*
G01X1438319Y562467D02*
X1439411Y561301D01*
X1440939Y560426D01*
X1442249D01*
X1443559Y561009D01*
X1444432Y561884D01*
X1444869Y563050D01*
X1444651Y564801D01*
X1443777Y565676D01*
X1439847Y567426D01*
X1438974Y569468D01*
X1439411Y570926D01*
X1440284Y571801D01*
X1441594Y572092D01*
X1442904Y571801D01*
X1444214Y570926D01*
G01X1459094Y572092D02*
Y560426D01*
G01Y576759D02*
X1458657Y577051D01*
Y577634D01*
X1459094Y577926D01*
X1459531Y577634D01*
Y577051D01*
X1459094Y576759D01*
G01X1480524Y577926D02*
Y560426D01*
G01Y563050D02*
X1479651Y561592D01*
X1478340Y560718D01*
X1476812Y560426D01*
X1475066Y561009D01*
X1473756Y562467D01*
X1472882Y564217D01*
X1472664Y566259D01*
X1472882Y568301D01*
X1473756Y570051D01*
X1475066Y571509D01*
X1476812Y572092D01*
X1478340Y571801D01*
X1479432Y571217D01*
X1480524Y570051D01*
G01X1490819Y568301D02*
X1497806D01*
X1497151Y570343D01*
X1496059Y571509D01*
X1494531Y572092D01*
X1493002Y571801D01*
X1491692Y570926D01*
X1490819Y568884D01*
X1490382Y567134D01*
Y565384D01*
X1490819Y563634D01*
X1491911Y561884D01*
X1493221Y560718D01*
X1494749Y560426D01*
X1496277Y561009D01*
X1497806Y562759D01*
G01X1525164Y560426D02*
Y577926D01*
G01Y569176D02*
X1526256Y570926D01*
X1527566Y571801D01*
X1528876Y572092D01*
X1530840Y571509D01*
X1532151Y570343D01*
X1533024Y568301D01*
Y565968D01*
X1532587Y563634D01*
X1531714Y561884D01*
X1530186Y560718D01*
X1528876Y560426D01*
X1527566Y560718D01*
X1526256Y561592D01*
X1525164Y563050D01*
G01X1546594Y560426D02*
X1545284Y560718D01*
X1543974Y561884D01*
X1543100Y563926D01*
X1542664Y566259D01*
X1543100Y568593D01*
X1543974Y570634D01*
X1545284Y571801D01*
X1546594Y572092D01*
X1547904Y571801D01*
X1549214Y570634D01*
X1550087Y568593D01*
X1550306Y566259D01*
X1550087Y563926D01*
X1549214Y561884D01*
X1547904Y560718D01*
X1546594Y560426D01*
G01X1568024D02*
Y572092D01*
G01Y570051D02*
X1567151Y571217D01*
X1565840Y571801D01*
X1564312Y572092D01*
X1562784Y571509D01*
X1561474Y570343D01*
X1560600Y568593D01*
X1560164Y566259D01*
X1560600Y563926D01*
X1561474Y562176D01*
X1562784Y561009D01*
X1564312Y560426D01*
X1565840Y560718D01*
X1567151Y561592D01*
X1568024Y562759D01*
G01X1578537Y560426D02*
Y572092D01*
G01Y569759D02*
X1579629Y570926D01*
X1580721Y571801D01*
X1582249Y572092D01*
X1583340Y571801D01*
X1584651Y570926D01*
G01X1603024Y577926D02*
Y560426D01*
G01Y563050D02*
X1602151Y561592D01*
X1600840Y560718D01*
X1599312Y560426D01*
X1597566Y561009D01*
X1596256Y562467D01*
X1595382Y564217D01*
X1595164Y566259D01*
X1595382Y568301D01*
X1596256Y570051D01*
X1597566Y571509D01*
X1599312Y572092D01*
X1600840Y571801D01*
X1601932Y571217D01*
X1603024Y570051D01*
G01X1634094Y560426D02*
X1632784Y560718D01*
X1631474Y561884D01*
X1630600Y563926D01*
X1630164Y566259D01*
X1630600Y568593D01*
X1631474Y570634D01*
X1632784Y571801D01*
X1634094Y572092D01*
X1635404Y571801D01*
X1636714Y570634D01*
X1637587Y568593D01*
X1637806Y566259D01*
X1637587Y563926D01*
X1636714Y561884D01*
X1635404Y560718D01*
X1634094Y560426D01*
G01X1647882Y572092D02*
Y563926D01*
X1648756Y561884D01*
X1650066Y560718D01*
X1651594Y560426D01*
X1653122Y560718D01*
X1654432Y561884D01*
X1655306Y563926D01*
G01Y560426D02*
Y572092D01*
G01X1669094Y577926D02*
Y560426D01*
G01X1666037Y572092D02*
X1672151D01*
G01X1686594Y560426D02*
Y577926D01*
G01X1704094Y572092D02*
Y560426D01*
G01Y576759D02*
X1703657Y577051D01*
Y577634D01*
X1704094Y577926D01*
X1704531Y577634D01*
Y577051D01*
X1704094Y576759D01*
G01X1717882Y560426D02*
Y572092D01*
G01Y569176D02*
X1718756Y570634D01*
X1720066Y571801D01*
X1721812Y572092D01*
X1723340Y571801D01*
X1724651Y570634D01*
X1725306Y568593D01*
Y560426D01*
G01X1735819Y568301D02*
X1742806D01*
X1742151Y570343D01*
X1741059Y571509D01*
X1739531Y572092D01*
X1738002Y571801D01*
X1736692Y570926D01*
X1735819Y568884D01*
X1735382Y567134D01*
Y565384D01*
X1735819Y563634D01*
X1736911Y561884D01*
X1738221Y560718D01*
X1739749Y560426D01*
X1741277Y561009D01*
X1742806Y562759D01*
G01X1756594Y559843D02*
X1756157Y560134D01*
Y560718D01*
X1756594Y561009D01*
X1757031Y560718D01*
Y560134D01*
X1756594Y559843D01*
G01X1331791Y629143D02*
X1341397Y641976D01*
G01X1336594Y644309D02*
Y626809D01*
G01X1341397Y629143D02*
X1331791Y641976D01*
G01X1330044Y635559D02*
X1343144D01*
G01X1368756D02*
X1374432D01*
G01X1401791Y629726D02*
Y647226D01*
X1406157D01*
X1407904Y646351D01*
X1409214Y645184D01*
X1410306Y643435D01*
X1411179Y641392D01*
X1411397Y638476D01*
X1411179Y635559D01*
X1410306Y633517D01*
X1409214Y631767D01*
X1407904Y630601D01*
X1406157Y629726D01*
X1401791D01*
G01X1420819Y637601D02*
X1427806D01*
X1427151Y639643D01*
X1426059Y640809D01*
X1424531Y641392D01*
X1423002Y641101D01*
X1421692Y640226D01*
X1420819Y638184D01*
X1420382Y636434D01*
Y634684D01*
X1420819Y632934D01*
X1421911Y631184D01*
X1423221Y630018D01*
X1424749Y629726D01*
X1426277Y630309D01*
X1427806Y632059D01*
G01X1437882Y629726D02*
Y641392D01*
G01Y638476D02*
X1438756Y639934D01*
X1440066Y641101D01*
X1441812Y641392D01*
X1443340Y641101D01*
X1444651Y639934D01*
X1445306Y637893D01*
Y629726D01*
G01X1459094D02*
X1457784Y630018D01*
X1456474Y631184D01*
X1455600Y633226D01*
X1455164Y635559D01*
X1455600Y637893D01*
X1456474Y639934D01*
X1457784Y641101D01*
X1459094Y641392D01*
X1460404Y641101D01*
X1461714Y639934D01*
X1462587Y637893D01*
X1462806Y635559D01*
X1462587Y633226D01*
X1461714Y631184D01*
X1460404Y630018D01*
X1459094Y629726D01*
G01X1476594Y647226D02*
Y629726D01*
G01X1473537Y641392D02*
X1479651D01*
G01X1490819Y637601D02*
X1497806D01*
X1497151Y639643D01*
X1496059Y640809D01*
X1494531Y641392D01*
X1493002Y641101D01*
X1491692Y640226D01*
X1490819Y638184D01*
X1490382Y636434D01*
Y634684D01*
X1490819Y632934D01*
X1491911Y631184D01*
X1493221Y630018D01*
X1494749Y629726D01*
X1496277Y630309D01*
X1497806Y632059D01*
G01X1508319Y631767D02*
X1509411Y630601D01*
X1510939Y629726D01*
X1512249D01*
X1513559Y630309D01*
X1514432Y631184D01*
X1514869Y632350D01*
X1514651Y634101D01*
X1513777Y634976D01*
X1509847Y636726D01*
X1508974Y638768D01*
X1509411Y640226D01*
X1510284Y641101D01*
X1511594Y641392D01*
X1512904Y641101D01*
X1514214Y640226D01*
G01X1546594Y647226D02*
Y629726D01*
G01X1543537Y641392D02*
X1549651D01*
G01X1560382Y629726D02*
Y647226D01*
G01Y638768D02*
X1561474Y640226D01*
X1562566Y641101D01*
X1564312Y641392D01*
X1565622Y641101D01*
X1567151Y639934D01*
X1567806Y638184D01*
Y629726D01*
G01X1585524D02*
Y641392D01*
G01Y639351D02*
X1584651Y640517D01*
X1583340Y641101D01*
X1581812Y641392D01*
X1580284Y640809D01*
X1578974Y639643D01*
X1578100Y637893D01*
X1577664Y635559D01*
X1578100Y633226D01*
X1578974Y631476D01*
X1580284Y630309D01*
X1581812Y629726D01*
X1583340Y630018D01*
X1584651Y630892D01*
X1585524Y632059D01*
G01X1599094Y647226D02*
Y629726D01*
G01X1596037Y641392D02*
X1602151D01*
G01X1627544Y647226D02*
X1630600Y629726D01*
X1634094Y647226D01*
X1637587Y629726D01*
X1640644Y647226D01*
G01X1648974D02*
X1654214D01*
G01X1651594D02*
Y629726D01*
G01X1648974D02*
X1654214D01*
G01X1664291D02*
Y647226D01*
X1668657D01*
X1670404Y646351D01*
X1671714Y645184D01*
X1672806Y643435D01*
X1673679Y641392D01*
X1673897Y638476D01*
X1673679Y635559D01*
X1672806Y633517D01*
X1671714Y631767D01*
X1670404Y630601D01*
X1668657Y629726D01*
X1664291D01*
G01X1686594Y647226D02*
Y629726D01*
G01X1681572Y647226D02*
X1691616D01*
G01X1699509Y629726D02*
Y647226D01*
G01X1708679D02*
Y629726D01*
G01Y638476D02*
X1699509D01*
G01X0Y-11811D02*
G03X7874Y-19685I7874J0D01*
G01X37008Y0D02*
G03Y-7874I0J-3937D01*
G01X11811D02*
G03Y0I0J3937D01*
G01X0Y-7874D02*
Y-11811D01*
G01X7874Y-19685D02*
X181690D01*
G01X0Y-7874D02*
X11811D01*
G01X25985Y19685D02*
G03X9449I-8268J0D01*
G01D02*
G03X25985I8268J0D01*
G01D02*
G03X9449I-8268J0D01*
G01D02*
G03X25985I8268J0D01*
G01D02*
G03X9449I-8268J0D01*
G01D02*
G03X25985I8268J0D01*
G01D02*
G03X9449I-8268J0D01*
G01D02*
G03X25985I8268J0D01*
G01X9449D02*
G03X25985I8268J0D01*
G01D02*
G03X9449I-8268J0D01*
G01D02*
G03X25985I8268J0D01*
G01D02*
G03X9449I-8268J0D01*
G01X3937Y0D02*
X173229D01*
G01X0Y3937D02*
G03X3937Y0I3937J0D01*
G01X0Y57874D02*
Y3937D01*
G01X37008Y69685D02*
G03Y61811I0J-3937D01*
G01X11811D02*
G03Y69685I0J3937D01*
G01X25985Y89370D02*
G03X9449I-8268J0D01*
G01D02*
G03X25985I8268J0D01*
G01D02*
G03X9449I-8268J0D01*
G01D02*
G03X25985I8268J0D01*
G01D02*
G03X9449I-8268J0D01*
G01D02*
G03X25985I8268J0D01*
G01D02*
G03X9449I-8268J0D01*
G01D02*
G03X25985I8268J0D01*
G01X9449D02*
G03X25985I8268J0D01*
G01D02*
G03X9449I-8268J0D01*
G01D02*
G03X25985I8268J0D01*
G01D02*
G03X9449I-8268J0D01*
G01X3937Y69685D02*
X173229D01*
G01X0Y73622D02*
G03X3937Y69685I3937J0D01*
G01X0Y127559D02*
Y73622D01*
G01X3937Y61811D02*
G03X0Y57874I0J-3937D01*
G01X173229Y61811D02*
X3937D01*
G01X37008Y139370D02*
G03Y131496I0J-3937D01*
G01X11811D02*
G03Y139370I0J3937D01*
G01X25985Y159055D02*
G03X9449I-8268J0D01*
G01D02*
G03X25985I8268J0D01*
G01D02*
G03X9449I-8268J0D01*
G01D02*
G03X25985I8268J0D01*
G01D02*
G03X9449I-8268J0D01*
G01D02*
G03X25985I8268J0D01*
G01D02*
G03X9449I-8268J0D01*
G01D02*
G03X25985I8268J0D01*
G01X9449D02*
G03X25985I8268J0D01*
G01D02*
G03X9449I-8268J0D01*
G01D02*
G03X25985I8268J0D01*
G01D02*
G03X9449I-8268J0D01*
G01X3937Y139370D02*
X173229D01*
G01X0Y143307D02*
G03X3937Y139370I3937J0D01*
G01X0Y197244D02*
Y143307D01*
G01X3937Y131496D02*
G03X0Y127559I0J-3937D01*
G01X173229Y131496D02*
X3937D01*
G01X37008Y278740D02*
G03Y270866I0J-3937D01*
G01X11811D02*
G03Y278740I0J3937D01*
G01X37008Y209055D02*
G03Y201181I0J-3937D01*
G01X11811D02*
G03Y209055I0J3937D01*
G01X3937Y278740D02*
X173229D01*
G01X0Y282677D02*
G03X3937Y278740I3937J0D01*
G01X25985Y228740D02*
G03X9449I-8268J0D01*
G01D02*
G03X25985I8268J0D01*
G01D02*
G03X9449I-8268J0D01*
G01D02*
G03X25985I8268J0D01*
G01D02*
G03X9449I-8268J0D01*
G01D02*
G03X25985I8268J0D01*
G01D02*
G03X9449I-8268J0D01*
G01D02*
G03X25985I8268J0D01*
G01X9449D02*
G03X25985I8268J0D01*
G01D02*
G03X9449I-8268J0D01*
G01D02*
G03X25985I8268J0D01*
G01D02*
G03X9449I-8268J0D01*
G01X3937Y209055D02*
X173229D01*
G01X0Y212992D02*
G03X3937Y209055I3937J0D01*
G01X0Y266929D02*
Y212992D01*
G01X3937Y270866D02*
G03X0Y266929I0J-3937D01*
G01X173229Y270866D02*
X3937D01*
G01Y201181D02*
G03X0Y197244I0J-3937D01*
G01X173229Y201181D02*
X3937D01*
G01X37008Y348425D02*
G03Y340551I0J-3937D01*
G01X11811D02*
G03Y348425I0J3937D01*
G01X9449Y368110D02*
G03X25985I8268J0D01*
G01X9449D02*
G03X25985I8268J0D01*
G01X9449D02*
G03X25985I8268J0D01*
G01X9449D02*
G03X25985I8268J0D01*
G01X9449D02*
G03X25985I8268J0D01*
G01X9449D02*
G03X25985I8268J0D01*
G01X3937Y348425D02*
X173229D01*
G01X0Y352362D02*
G03X3937Y348425I3937J0D01*
G01X0Y406299D02*
Y352362D01*
G01X25985Y298425D02*
G03X9449I-8268J0D01*
G01D02*
G03X25985I8268J0D01*
G01D02*
G03X9449I-8268J0D01*
G01D02*
G03X25985I8268J0D01*
G01D02*
G03X9449I-8268J0D01*
G01D02*
G03X25985I8268J0D01*
G01D02*
G03X9449I-8268J0D01*
G01D02*
G03X25985I8268J0D01*
G01X9449D02*
G03X25985I8268J0D01*
G01D02*
G03X9449I-8268J0D01*
G01D02*
G03X25985I8268J0D01*
G01D02*
G03X9449I-8268J0D01*
G01X0Y336614D02*
Y282677D01*
G01X3937Y340551D02*
G03X0Y336614I0J-3937D01*
G01X173229Y340551D02*
X3937D01*
G01X37008Y418110D02*
G03Y410236I0J-3937D01*
G01X11811D02*
G03Y418110I0J3937D01*
G01X25985Y437795D02*
G03X9449I-8268J0D01*
G01D02*
G03X25985I8268J0D01*
G01D02*
G03X9449I-8268J0D01*
G01D02*
G03X25985I8268J0D01*
G01D02*
G03X9449I-8268J0D01*
G01D02*
G03X25985I8268J0D01*
G01D02*
G03X9449I-8268J0D01*
G01D02*
G03X25985I8268J0D01*
G01X9449D02*
G03X25985I8268J0D01*
G01D02*
G03X9449I-8268J0D01*
G01D02*
G03X25985I8268J0D01*
G01D02*
G03X9449I-8268J0D01*
G01X3937Y418110D02*
X173229D01*
G01X0Y422047D02*
G03X3937Y418110I3937J0D01*
G01X0Y475984D02*
Y422047D01*
G01X25985Y368110D02*
G03X9449I-8268J0D01*
G01X25985D02*
G03X9449I-8268J0D01*
G01X25985D02*
G03X9449I-8268J0D01*
G01X25985D02*
G03X9449I-8268J0D01*
G01X25985D02*
G03X9449I-8268J0D01*
G01X25985D02*
G03X9449I-8268J0D01*
G01X3937Y410236D02*
G03X0Y406299I0J-3937D01*
G01X173229Y410236D02*
X3937D01*
G01X37008Y487795D02*
G03Y479921I0J-3937D01*
G01X11811D02*
G03Y487795I0J3937D01*
G01X25985Y507480D02*
G03X9449I-8268J0D01*
G01D02*
G03X25985I8268J0D01*
G01D02*
G03X9449I-8268J0D01*
G01D02*
G03X25985I8268J0D01*
G01D02*
G03X9449I-8268J0D01*
G01D02*
G03X25985I8268J0D01*
G01D02*
G03X9449I-8268J0D01*
G01D02*
G03X25985I8268J0D01*
G01X9449D02*
G03X25985I8268J0D01*
G01D02*
G03X9449I-8268J0D01*
G01D02*
G03X25985I8268J0D01*
G01D02*
G03X9449I-8268J0D01*
G01X3937Y487795D02*
X173229D01*
G01X0Y491732D02*
G03X3937Y487795I3937J0D01*
G01X0Y545669D02*
Y491732D01*
G01X3937Y479921D02*
G03X0Y475984I0J-3937D01*
G01X173229Y479921D02*
X3937D01*
G01X37008Y557480D02*
G03Y549606I0J-3937D01*
G01X11811D02*
G03Y557480I0J3937D01*
G01X25985Y577165D02*
G03X9449I-8268J0D01*
G01D02*
G03X25985I8268J0D01*
G01D02*
G03X9449I-8268J0D01*
G01D02*
G03X25985I8268J0D01*
G01D02*
G03X9449I-8268J0D01*
G01D02*
G03X25985I8268J0D01*
G01D02*
G03X9449I-8268J0D01*
G01D02*
G03X25985I8268J0D01*
G01X9449D02*
G03X25985I8268J0D01*
G01D02*
G03X9449I-8268J0D01*
G01D02*
G03X25985I8268J0D01*
G01D02*
G03X9449I-8268J0D01*
G01X3937Y557480D02*
X173229D01*
G01X0Y561417D02*
G03X3937Y557480I3937J0D01*
G01X0Y615354D02*
Y561417D01*
G01X3937Y549606D02*
G03X0Y545669I0J-3937D01*
G01X173229Y549606D02*
X3937D01*
G01X37008Y627165D02*
G03Y619291I0J-3937D01*
G01X11811D02*
G03Y627165I0J3937D01*
G01X25985Y646850D02*
G03X9449I-8268J0D01*
G01D02*
G03X25985I8268J0D01*
G01D02*
G03X9449I-8268J0D01*
G01D02*
G03X25985I8268J0D01*
G01D02*
G03X9449I-8268J0D01*
G01D02*
G03X25985I8268J0D01*
G01D02*
G03X9449I-8268J0D01*
G01D02*
G03X25985I8268J0D01*
G01X9449D02*
G03X25985I8268J0D01*
G01D02*
G03X9449I-8268J0D01*
G01D02*
G03X25985I8268J0D01*
G01D02*
G03X9449I-8268J0D01*
G01X3937Y627165D02*
X173229D01*
G01X0Y631102D02*
G03X3937Y627165I3937J0D01*
G01X0Y685039D02*
Y631102D01*
G01X3937Y688976D02*
G03X0Y685039I0J-3937D01*
G01X173229Y688976D02*
X3937D01*
G01Y619291D02*
G03X0Y615354I0J-3937D01*
G01X173229Y619291D02*
X3937D01*
G01X37008Y-7874D02*
X140158D01*
G01X196851D02*
G03Y0I0J3937D01*
G01X189564Y-19685D02*
G03X181690I-3937J0D01*
G01X165355Y0D02*
G03Y-7874I0J-3937D01*
G01X140158D02*
G03Y0I0J3937D01*
G01X185040Y18307D02*
G03X177166I-3937J0D01*
G01X189564Y-19685D02*
X539370D01*
G01X165355Y-7874D02*
X196851D01*
G01X211024Y19685D02*
G03X194489I-8267J0D01*
G01D02*
G03X211024I8267J0D01*
G01D02*
G03X194489I-8267J0D01*
G01D02*
G03X211024I8267J0D01*
G01D02*
G03X194489I-8267J0D01*
G01D02*
G03X211024I8267J0D01*
G01D02*
G03X194489I-8267J0D01*
G01D02*
G03X211024I8267J0D01*
G01X194489D02*
G03X211024I8267J0D01*
G01D02*
G03X194489I-8267J0D01*
G01D02*
G03X211024I8267J0D01*
G01D02*
G03X194489I-8267J0D01*
G01X188977Y0D02*
X358268D01*
G01X185040Y3937D02*
G03X188977Y0I3937J0D01*
G01X185040Y57874D02*
Y3937D01*
G01X167717Y19685D02*
G03X151181I-8268J0D01*
G01D02*
G03X167717I8268J0D01*
G01D02*
G03X151181I-8268J0D01*
G01D02*
G03X167717I8268J0D01*
G01D02*
G03X151181I-8268J0D01*
G01D02*
G03X167717I8268J0D01*
G01D02*
G03X151181I-8268J0D01*
G01D02*
G03X167717I8268J0D01*
G01X151181D02*
G03X167717I8268J0D01*
G01D02*
G03X151181I-8268J0D01*
G01D02*
G03X167717I8268J0D01*
G01D02*
G03X151181I-8268J0D01*
G01X177166Y3937D02*
Y57874D01*
G01X173229Y0D02*
G03X177166Y3937I0J3937D01*
G01X185040Y87992D02*
G03X177166I-3937J0D01*
G01Y113189D02*
G03X185040I3937J0D01*
G01X196851Y61811D02*
G03Y69685I0J3937D01*
G01X165355D02*
G03Y61811I0J-3937D01*
G01X140158D02*
G03Y69685I0J3937D01*
G01X177166Y43504D02*
G03X185040I3937J0D01*
G01X167717Y89370D02*
G03X151181I-8268J0D01*
G01D02*
G03X167717I8268J0D01*
G01D02*
G03X151181I-8268J0D01*
G01D02*
G03X167717I8268J0D01*
G01D02*
G03X151181I-8268J0D01*
G01D02*
G03X167717I8268J0D01*
G01D02*
G03X151181I-8268J0D01*
G01D02*
G03X167717I8268J0D01*
G01X151181D02*
G03X167717I8268J0D01*
G01D02*
G03X151181I-8268J0D01*
G01D02*
G03X167717I8268J0D01*
G01D02*
G03X151181I-8268J0D01*
G01X177166Y73622D02*
Y127559D01*
G01X173229Y69685D02*
G03X177166Y73622I0J3937D01*
G01X211024Y89370D02*
G03X194489I-8267J0D01*
G01D02*
G03X211024I8267J0D01*
G01D02*
G03X194489I-8267J0D01*
G01D02*
G03X211024I8267J0D01*
G01D02*
G03X194489I-8267J0D01*
G01D02*
G03X211024I8267J0D01*
G01D02*
G03X194489I-8267J0D01*
G01D02*
G03X211024I8267J0D01*
G01X194489D02*
G03X211024I8267J0D01*
G01D02*
G03X194489I-8267J0D01*
G01D02*
G03X211024I8267J0D01*
G01D02*
G03X194489I-8267J0D01*
G01X188977Y69685D02*
X358268D01*
G01X185040Y73622D02*
G03X188977Y69685I3937J0D01*
G01X185040Y127559D02*
Y73622D01*
G01X188977Y61811D02*
G03X185040Y57874I0J-3937D01*
G01X358268Y61811D02*
X188977D01*
G01X177166Y57874D02*
G03X173229Y61811I-3937J0D01*
G01X185040Y157677D02*
G03X177166I-3937J0D01*
G01Y182874D02*
G03X185040I3937J0D01*
G01X196851Y131496D02*
G03Y139370I0J3937D01*
G01X165355D02*
G03Y131496I0J-3937D01*
G01X140158D02*
G03Y139370I0J3937D01*
G01X167717Y159055D02*
G03X151181I-8268J0D01*
G01D02*
G03X167717I8268J0D01*
G01D02*
G03X151181I-8268J0D01*
G01D02*
G03X167717I8268J0D01*
G01D02*
G03X151181I-8268J0D01*
G01D02*
G03X167717I8268J0D01*
G01D02*
G03X151181I-8268J0D01*
G01D02*
G03X167717I8268J0D01*
G01X151181D02*
G03X167717I8268J0D01*
G01D02*
G03X151181I-8268J0D01*
G01D02*
G03X167717I8268J0D01*
G01D02*
G03X151181I-8268J0D01*
G01X177166Y143307D02*
Y197244D01*
G01X173229Y139370D02*
G03X177166Y143307I0J3937D01*
G01Y127559D02*
G03X173229Y131496I-3937J0D01*
G01X211024Y159055D02*
G03X194489I-8267J0D01*
G01D02*
G03X211024I8267J0D01*
G01D02*
G03X194489I-8267J0D01*
G01D02*
G03X211024I8267J0D01*
G01D02*
G03X194489I-8267J0D01*
G01D02*
G03X211024I8267J0D01*
G01D02*
G03X194489I-8267J0D01*
G01D02*
G03X211024I8267J0D01*
G01X194489D02*
G03X211024I8267J0D01*
G01D02*
G03X194489I-8267J0D01*
G01D02*
G03X211024I8267J0D01*
G01D02*
G03X194489I-8267J0D01*
G01X188977Y139370D02*
X358268D01*
G01X185040Y143307D02*
G03X188977Y139370I3937J0D01*
G01X185040Y197244D02*
Y143307D01*
G01X188977Y131496D02*
G03X185040Y127559I0J-3937D01*
G01X358268Y131496D02*
X188977D01*
G01X185040Y227362D02*
G03X177166I-3937J0D01*
G01Y252559D02*
G03X185040I3937J0D01*
G01X196851Y270866D02*
G03Y278740I0J3937D01*
G01X165355D02*
G03Y270866I0J-3937D01*
G01X140158D02*
G03Y278740I0J3937D01*
G01X196851Y201181D02*
G03Y209055I0J3937D01*
G01X165355D02*
G03Y201181I0J-3937D01*
G01X140158D02*
G03Y209055I0J3937D01*
G01X173229Y278740D02*
G03X177166Y282677I0J3937D01*
G01X188977Y278740D02*
X358268D01*
G01X185040Y282677D02*
G03X188977Y278740I3937J0D01*
G01X167717Y228740D02*
G03X151181I-8268J0D01*
G01D02*
G03X167717I8268J0D01*
G01D02*
G03X151181I-8268J0D01*
G01D02*
G03X167717I8268J0D01*
G01D02*
G03X151181I-8268J0D01*
G01D02*
G03X167717I8268J0D01*
G01D02*
G03X151181I-8268J0D01*
G01D02*
G03X167717I8268J0D01*
G01X151181D02*
G03X167717I8268J0D01*
G01D02*
G03X151181I-8268J0D01*
G01D02*
G03X167717I8268J0D01*
G01D02*
G03X151181I-8268J0D01*
G01X177166Y212992D02*
Y266929D01*
G01X173229Y209055D02*
G03X177166Y212992I0J3937D01*
G01Y266929D02*
G03X173229Y270866I-3937J0D01*
G01X211024Y228740D02*
G03X194489I-8267J0D01*
G01D02*
G03X211024I8267J0D01*
G01D02*
G03X194489I-8267J0D01*
G01D02*
G03X211024I8267J0D01*
G01D02*
G03X194489I-8267J0D01*
G01D02*
G03X211024I8267J0D01*
G01D02*
G03X194489I-8267J0D01*
G01D02*
G03X211024I8267J0D01*
G01X194489D02*
G03X211024I8267J0D01*
G01D02*
G03X194489I-8267J0D01*
G01D02*
G03X211024I8267J0D01*
G01D02*
G03X194489I-8267J0D01*
G01X188977Y209055D02*
X358268D01*
G01X185040Y212992D02*
G03X188977Y209055I3937J0D01*
G01X185040Y266929D02*
Y212992D01*
G01X188977Y270866D02*
G03X185040Y266929I0J-3937D01*
G01X358268Y270866D02*
X188977D01*
G01X177166Y197244D02*
G03X173229Y201181I-3937J0D01*
G01X188977D02*
G03X185040Y197244I0J-3937D01*
G01X358268Y201181D02*
X188977D01*
G01X185040Y297047D02*
G03X177166I-3937J0D01*
G01Y322244D02*
G03X185040I3937J0D01*
G01X196851Y340551D02*
G03Y348425I0J3937D01*
G01X165355D02*
G03Y340551I0J-3937D01*
G01X140158D02*
G03Y348425I0J3937D01*
G01X151181Y368110D02*
G03X167717I8268J0D01*
G01X151181D02*
G03X167717I8268J0D01*
G01X151181D02*
G03X167717I8268J0D01*
G01X151181D02*
G03X167717I8268J0D01*
G01X151181D02*
G03X167717I8268J0D01*
G01X151181D02*
G03X167717I8268J0D01*
G01X177166Y352362D02*
Y406299D01*
G01X173229Y348425D02*
G03X177166Y352362I0J3937D01*
G01X194489Y368110D02*
G03X211024I8267J0D01*
G01X194489D02*
G03X211024I8267J0D01*
G01X194489D02*
G03X211024I8267J0D01*
G01X194489D02*
G03X211024I8267J0D01*
G01X194489D02*
G03X211024I8267J0D01*
G01X194489D02*
G03X211024I8267J0D01*
G01X188977Y348425D02*
X358268D01*
G01X185040Y352362D02*
G03X188977Y348425I3937J0D01*
G01X185040Y406299D02*
Y352362D01*
G01X167717Y298425D02*
G03X151181I-8268J0D01*
G01D02*
G03X167717I8268J0D01*
G01D02*
G03X151181I-8268J0D01*
G01D02*
G03X167717I8268J0D01*
G01D02*
G03X151181I-8268J0D01*
G01D02*
G03X167717I8268J0D01*
G01D02*
G03X151181I-8268J0D01*
G01D02*
G03X167717I8268J0D01*
G01X151181D02*
G03X167717I8268J0D01*
G01D02*
G03X151181I-8268J0D01*
G01D02*
G03X167717I8268J0D01*
G01D02*
G03X151181I-8268J0D01*
G01X177166Y282677D02*
Y336614D01*
G01D02*
G03X173229Y340551I-3937J0D01*
G01X211024Y298425D02*
G03X194489I-8267J0D01*
G01D02*
G03X211024I8267J0D01*
G01D02*
G03X194489I-8267J0D01*
G01D02*
G03X211024I8267J0D01*
G01D02*
G03X194489I-8267J0D01*
G01D02*
G03X211024I8267J0D01*
G01D02*
G03X194489I-8267J0D01*
G01D02*
G03X211024I8267J0D01*
G01X194489D02*
G03X211024I8267J0D01*
G01D02*
G03X194489I-8267J0D01*
G01D02*
G03X211024I8267J0D01*
G01D02*
G03X194489I-8267J0D01*
G01X185040Y336614D02*
Y282677D01*
G01X188977Y340551D02*
G03X185040Y336614I0J-3937D01*
G01X358268Y340551D02*
X188977D01*
G01X185040Y436417D02*
G03X177166I-3937J0D01*
G01X185040Y366732D02*
G03X177166I-3937J0D01*
G01Y391929D02*
G03X185040I3937J0D01*
G01X196851Y410236D02*
G03Y418110I0J3937D01*
G01X165355D02*
G03Y410236I0J-3937D01*
G01X140158D02*
G03Y418110I0J3937D01*
G01X167717Y437795D02*
G03X151181I-8268J0D01*
G01D02*
G03X167717I8268J0D01*
G01D02*
G03X151181I-8268J0D01*
G01D02*
G03X167717I8268J0D01*
G01D02*
G03X151181I-8268J0D01*
G01D02*
G03X167717I8268J0D01*
G01D02*
G03X151181I-8268J0D01*
G01D02*
G03X167717I8268J0D01*
G01X151181D02*
G03X167717I8268J0D01*
G01D02*
G03X151181I-8268J0D01*
G01D02*
G03X167717I8268J0D01*
G01D02*
G03X151181I-8268J0D01*
G01X177166Y422047D02*
Y475984D01*
G01X173229Y418110D02*
G03X177166Y422047I0J3937D01*
G01X211024Y437795D02*
G03X194489I-8267J0D01*
G01D02*
G03X211024I8267J0D01*
G01D02*
G03X194489I-8267J0D01*
G01D02*
G03X211024I8267J0D01*
G01D02*
G03X194489I-8267J0D01*
G01D02*
G03X211024I8267J0D01*
G01D02*
G03X194489I-8267J0D01*
G01D02*
G03X211024I8267J0D01*
G01X194489D02*
G03X211024I8267J0D01*
G01D02*
G03X194489I-8267J0D01*
G01D02*
G03X211024I8267J0D01*
G01D02*
G03X194489I-8267J0D01*
G01X188977Y418110D02*
X358268D01*
G01X185040Y422047D02*
G03X188977Y418110I3937J0D01*
G01X185040Y475984D02*
Y422047D01*
G01X167717Y368110D02*
G03X151181I-8268J0D01*
G01X167717D02*
G03X151181I-8268J0D01*
G01X167717D02*
G03X151181I-8268J0D01*
G01X167717D02*
G03X151181I-8268J0D01*
G01X167717D02*
G03X151181I-8268J0D01*
G01X167717D02*
G03X151181I-8268J0D01*
G01X177166Y406299D02*
G03X173229Y410236I-3937J0D01*
G01X211024Y368110D02*
G03X194489I-8267J0D01*
G01X211024D02*
G03X194489I-8267J0D01*
G01X211024D02*
G03X194489I-8267J0D01*
G01X211024D02*
G03X194489I-8267J0D01*
G01X211024D02*
G03X194489I-8267J0D01*
G01X211024D02*
G03X194489I-8267J0D01*
G01X188977Y410236D02*
G03X185040Y406299I0J-3937D01*
G01X358268Y410236D02*
X188977D01*
G01X185040Y506102D02*
G03X177166I-3937J0D01*
G01Y531299D02*
G03X185040I3937J0D01*
G01X177166Y461614D02*
G03X185040I3937J0D01*
G01X196851Y479921D02*
G03Y487795I0J3937D01*
G01X165355D02*
G03Y479921I0J-3937D01*
G01X140158D02*
G03Y487795I0J3937D01*
G01X167717Y507480D02*
G03X151181I-8268J0D01*
G01D02*
G03X167717I8268J0D01*
G01D02*
G03X151181I-8268J0D01*
G01D02*
G03X167717I8268J0D01*
G01D02*
G03X151181I-8268J0D01*
G01D02*
G03X167717I8268J0D01*
G01D02*
G03X151181I-8268J0D01*
G01D02*
G03X167717I8268J0D01*
G01X151181D02*
G03X167717I8268J0D01*
G01D02*
G03X151181I-8268J0D01*
G01D02*
G03X167717I8268J0D01*
G01D02*
G03X151181I-8268J0D01*
G01X177166Y491732D02*
Y545669D01*
G01X173229Y487795D02*
G03X177166Y491732I0J3937D01*
G01X211024Y507480D02*
G03X194489I-8267J0D01*
G01D02*
G03X211024I8267J0D01*
G01D02*
G03X194489I-8267J0D01*
G01D02*
G03X211024I8267J0D01*
G01D02*
G03X194489I-8267J0D01*
G01D02*
G03X211024I8267J0D01*
G01D02*
G03X194489I-8267J0D01*
G01D02*
G03X211024I8267J0D01*
G01X194489D02*
G03X211024I8267J0D01*
G01D02*
G03X194489I-8267J0D01*
G01D02*
G03X211024I8267J0D01*
G01D02*
G03X194489I-8267J0D01*
G01X188977Y487795D02*
X358268D01*
G01X185040Y491732D02*
G03X188977Y487795I3937J0D01*
G01X185040Y545669D02*
Y491732D01*
G01X177166Y475984D02*
G03X173229Y479921I-3937J0D01*
G01X188977D02*
G03X185040Y475984I0J-3937D01*
G01X358268Y479921D02*
X188977D01*
G01X185040Y575787D02*
G03X177166I-3937J0D01*
G01Y600984D02*
G03X185040I3937J0D01*
G01X196851Y549606D02*
G03Y557480I0J3937D01*
G01X165355D02*
G03Y549606I0J-3937D01*
G01X140158D02*
G03Y557480I0J3937D01*
G01X167717Y577165D02*
G03X151181I-8268J0D01*
G01D02*
G03X167717I8268J0D01*
G01D02*
G03X151181I-8268J0D01*
G01D02*
G03X167717I8268J0D01*
G01D02*
G03X151181I-8268J0D01*
G01D02*
G03X167717I8268J0D01*
G01D02*
G03X151181I-8268J0D01*
G01D02*
G03X167717I8268J0D01*
G01X151181D02*
G03X167717I8268J0D01*
G01D02*
G03X151181I-8268J0D01*
G01D02*
G03X167717I8268J0D01*
G01D02*
G03X151181I-8268J0D01*
G01X177166Y561417D02*
Y615354D01*
G01X173229Y557480D02*
G03X177166Y561417I0J3937D01*
G01X211024Y577165D02*
G03X194489I-8267J0D01*
G01D02*
G03X211024I8267J0D01*
G01D02*
G03X194489I-8267J0D01*
G01D02*
G03X211024I8267J0D01*
G01D02*
G03X194489I-8267J0D01*
G01D02*
G03X211024I8267J0D01*
G01D02*
G03X194489I-8267J0D01*
G01D02*
G03X211024I8267J0D01*
G01X194489D02*
G03X211024I8267J0D01*
G01D02*
G03X194489I-8267J0D01*
G01D02*
G03X211024I8267J0D01*
G01D02*
G03X194489I-8267J0D01*
G01X188977Y557480D02*
X358268D01*
G01X185040Y561417D02*
G03X188977Y557480I3937J0D01*
G01X185040Y615354D02*
Y561417D01*
G01X177166Y545669D02*
G03X173229Y549606I-3937J0D01*
G01X188977D02*
G03X185040Y545669I0J-3937D01*
G01X358268Y549606D02*
X188977D01*
G01X185040Y645472D02*
G03X177166I-3937J0D01*
G01Y670669D02*
G03X185040I3937J0D01*
G01X196851Y619291D02*
G03Y627165I0J3937D01*
G01X165355D02*
G03Y619291I0J-3937D01*
G01X140158D02*
G03Y627165I0J3937D01*
G01X167717Y646850D02*
G03X151181I-8268J0D01*
G01D02*
G03X167717I8268J0D01*
G01D02*
G03X151181I-8268J0D01*
G01D02*
G03X167717I8268J0D01*
G01D02*
G03X151181I-8268J0D01*
G01D02*
G03X167717I8268J0D01*
G01D02*
G03X151181I-8268J0D01*
G01D02*
G03X167717I8268J0D01*
G01X151181D02*
G03X167717I8268J0D01*
G01D02*
G03X151181I-8268J0D01*
G01D02*
G03X167717I8268J0D01*
G01D02*
G03X151181I-8268J0D01*
G01X177166Y631102D02*
Y685039D01*
G01X173229Y627165D02*
G03X177166Y631102I0J3937D01*
G01Y685039D02*
G03X173229Y688976I-3937J0D01*
G01X211024Y646850D02*
G03X194489I-8267J0D01*
G01D02*
G03X211024I8267J0D01*
G01D02*
G03X194489I-8267J0D01*
G01D02*
G03X211024I8267J0D01*
G01D02*
G03X194489I-8267J0D01*
G01D02*
G03X211024I8267J0D01*
G01D02*
G03X194489I-8267J0D01*
G01D02*
G03X211024I8267J0D01*
G01X194489D02*
G03X211024I8267J0D01*
G01D02*
G03X194489I-8267J0D01*
G01D02*
G03X211024I8267J0D01*
G01D02*
G03X194489I-8267J0D01*
G01X188977Y627165D02*
X358268D01*
G01X185040Y631102D02*
G03X188977Y627165I3937J0D01*
G01X185040Y685039D02*
Y631102D01*
G01X188977Y688976D02*
G03X185040Y685039I0J-3937D01*
G01X358268Y688976D02*
X188977D01*
G01X177166Y615354D02*
G03X173229Y619291I-3937J0D01*
G01X188977D02*
G03X185040Y615354I0J-3937D01*
G01X358268Y619291D02*
X188977D01*
G01X222048Y0D02*
G03Y-7874I0J-3937D01*
G01D02*
X325197D01*
G01X222048Y69685D02*
G03Y61811I0J-3937D01*
G01Y139370D02*
G03Y131496I0J-3937D01*
G01Y278740D02*
G03Y270866I0J-3937D01*
G01Y209055D02*
G03Y201181I0J-3937D01*
G01Y348425D02*
G03Y340551I0J-3937D01*
G01Y418110D02*
G03Y410236I0J-3937D01*
G01Y487795D02*
G03Y479921I0J-3937D01*
G01Y557480D02*
G03Y549606I0J-3937D01*
G01Y627165D02*
G03Y619291I0J-3937D01*
G01X370079Y18307D02*
G03X362205I-3937J0D01*
G01X350394Y0D02*
G03Y-7874I0J-3937D01*
G01X325197D02*
G03Y0I0J3937D01*
G01X350394Y-7874D02*
X381890D01*
G01X352756Y19685D02*
G03X336221I-8267J0D01*
G01D02*
G03X352756I8268J0D01*
G01D02*
G03X336221I-8267J0D01*
G01D02*
G03X352756I8268J0D01*
G01D02*
G03X336221I-8267J0D01*
G01D02*
G03X352756I8268J0D01*
G01D02*
G03X336221I-8267J0D01*
G01D02*
G03X352756I8268J0D01*
G01X336221D02*
G03X352756I8268J0D01*
G01D02*
G03X336221I-8267J0D01*
G01D02*
G03X352756I8268J0D01*
G01D02*
G03X336221I-8267J0D01*
G01X362205Y3937D02*
Y57874D01*
G01X358268Y0D02*
G03X362205Y3937I0J3937D01*
G01X370079Y87992D02*
G03X362205I-3937J0D01*
G01Y113189D02*
G03X370079I3937J0D01*
G01X362205Y43504D02*
G03X370079I3937J0D01*
G01X350394Y69685D02*
G03Y61811I0J-3937D01*
G01X325197D02*
G03Y69685I0J3937D01*
G01X352756Y89370D02*
G03X336221I-8267J0D01*
G01D02*
G03X352756I8268J0D01*
G01D02*
G03X336221I-8267J0D01*
G01D02*
G03X352756I8268J0D01*
G01D02*
G03X336221I-8267J0D01*
G01D02*
G03X352756I8268J0D01*
G01D02*
G03X336221I-8267J0D01*
G01D02*
G03X352756I8268J0D01*
G01X336221D02*
G03X352756I8268J0D01*
G01D02*
G03X336221I-8267J0D01*
G01D02*
G03X352756I8268J0D01*
G01D02*
G03X336221I-8267J0D01*
G01X362205Y73622D02*
Y127559D01*
G01X358268Y69685D02*
G03X362205Y73622I0J3937D01*
G01Y57874D02*
G03X358268Y61811I-3937J0D01*
G01X370079Y157677D02*
G03X362205I-3937J0D01*
G01Y182874D02*
G03X370079I3937J0D01*
G01X350394Y139370D02*
G03Y131496I0J-3937D01*
G01X325197D02*
G03Y139370I0J3937D01*
G01X352756Y159055D02*
G03X336221I-8267J0D01*
G01D02*
G03X352756I8268J0D01*
G01D02*
G03X336221I-8267J0D01*
G01D02*
G03X352756I8268J0D01*
G01D02*
G03X336221I-8267J0D01*
G01D02*
G03X352756I8268J0D01*
G01D02*
G03X336221I-8267J0D01*
G01D02*
G03X352756I8268J0D01*
G01X336221D02*
G03X352756I8268J0D01*
G01D02*
G03X336221I-8267J0D01*
G01D02*
G03X352756I8268J0D01*
G01D02*
G03X336221I-8267J0D01*
G01X362205Y143307D02*
Y197244D01*
G01X358268Y139370D02*
G03X362205Y143307I0J3937D01*
G01Y127559D02*
G03X358268Y131496I-3937J0D01*
G01X370079Y227362D02*
G03X362205I-3937J0D01*
G01Y252559D02*
G03X370079I3937J0D01*
G01X350394Y278740D02*
G03Y270866I0J-3937D01*
G01X325197D02*
G03Y278740I0J3937D01*
G01X350394Y209055D02*
G03Y201181I0J-3937D01*
G01X325197D02*
G03Y209055I0J3937D01*
G01X358268Y278740D02*
G03X362205Y282677I0J3937D01*
G01X352756Y228740D02*
G03X336221I-8267J0D01*
G01D02*
G03X352756I8268J0D01*
G01D02*
G03X336221I-8267J0D01*
G01D02*
G03X352756I8268J0D01*
G01D02*
G03X336221I-8267J0D01*
G01D02*
G03X352756I8268J0D01*
G01D02*
G03X336221I-8267J0D01*
G01D02*
G03X352756I8268J0D01*
G01X336221D02*
G03X352756I8268J0D01*
G01D02*
G03X336221I-8267J0D01*
G01D02*
G03X352756I8268J0D01*
G01D02*
G03X336221I-8267J0D01*
G01X362205Y212992D02*
Y266929D01*
G01X358268Y209055D02*
G03X362205Y212992I0J3937D01*
G01Y266929D02*
G03X358268Y270866I-3937J0D01*
G01X362205Y197244D02*
G03X358268Y201181I-3937J0D01*
G01X370079Y297047D02*
G03X362205I-3937J0D01*
G01Y322244D02*
G03X370079I3937J0D01*
G01X350394Y348425D02*
G03Y340551I0J-3937D01*
G01X325197D02*
G03Y348425I0J3937D01*
G01X336221Y368110D02*
G03X352756I8268J0D01*
G01X336221D02*
G03X352756I8268J0D01*
G01X336221D02*
G03X352756I8268J0D01*
G01X336221D02*
G03X352756I8268J0D01*
G01X336221D02*
G03X352756I8268J0D01*
G01X336221D02*
G03X352756I8268J0D01*
G01X362205Y352362D02*
Y406299D01*
G01X358268Y348425D02*
G03X362205Y352362I0J3937D01*
G01X352756Y298425D02*
G03X336221I-8267J0D01*
G01D02*
G03X352756I8268J0D01*
G01D02*
G03X336221I-8267J0D01*
G01D02*
G03X352756I8268J0D01*
G01D02*
G03X336221I-8267J0D01*
G01D02*
G03X352756I8268J0D01*
G01D02*
G03X336221I-8267J0D01*
G01D02*
G03X352756I8268J0D01*
G01X336221D02*
G03X352756I8268J0D01*
G01D02*
G03X336221I-8267J0D01*
G01D02*
G03X352756I8268J0D01*
G01D02*
G03X336221I-8267J0D01*
G01X362205Y282677D02*
Y336614D01*
G01D02*
G03X358268Y340551I-3937J0D01*
G01X370079Y436417D02*
G03X362205I-3937J0D01*
G01X370079Y366732D02*
G03X362205I-3937J0D01*
G01Y391929D02*
G03X370079I3937J0D01*
G01X350394Y418110D02*
G03Y410236I0J-3937D01*
G01X325197D02*
G03Y418110I0J3937D01*
G01X352756Y437795D02*
G03X336221I-8267J0D01*
G01D02*
G03X352756I8268J0D01*
G01D02*
G03X336221I-8267J0D01*
G01D02*
G03X352756I8268J0D01*
G01D02*
G03X336221I-8267J0D01*
G01D02*
G03X352756I8268J0D01*
G01D02*
G03X336221I-8267J0D01*
G01D02*
G03X352756I8268J0D01*
G01X336221D02*
G03X352756I8268J0D01*
G01D02*
G03X336221I-8267J0D01*
G01D02*
G03X352756I8268J0D01*
G01D02*
G03X336221I-8267J0D01*
G01X362205Y422047D02*
Y475984D01*
G01X358268Y418110D02*
G03X362205Y422047I0J3937D01*
G01X352756Y368110D02*
G03X336221I-8267J0D01*
G01X352756D02*
G03X336221I-8267J0D01*
G01X352756D02*
G03X336221I-8267J0D01*
G01X352756D02*
G03X336221I-8267J0D01*
G01X352756D02*
G03X336221I-8267J0D01*
G01X352756D02*
G03X336221I-8267J0D01*
G01X362205Y406299D02*
G03X358268Y410236I-3937J0D01*
G01X370079Y506102D02*
G03X362205I-3937J0D01*
G01Y531299D02*
G03X370079I3937J0D01*
G01X362205Y461614D02*
G03X370079I3937J0D01*
G01X350394Y487795D02*
G03Y479921I0J-3937D01*
G01X325197D02*
G03Y487795I0J3937D01*
G01X352756Y507480D02*
G03X336221I-8267J0D01*
G01D02*
G03X352756I8268J0D01*
G01D02*
G03X336221I-8267J0D01*
G01D02*
G03X352756I8268J0D01*
G01D02*
G03X336221I-8267J0D01*
G01D02*
G03X352756I8268J0D01*
G01D02*
G03X336221I-8267J0D01*
G01D02*
G03X352756I8268J0D01*
G01X336221D02*
G03X352756I8268J0D01*
G01D02*
G03X336221I-8267J0D01*
G01D02*
G03X352756I8268J0D01*
G01D02*
G03X336221I-8267J0D01*
G01X362205Y491732D02*
Y545669D01*
G01X358268Y487795D02*
G03X362205Y491732I0J3937D01*
G01Y475984D02*
G03X358268Y479921I-3937J0D01*
G01X370079Y575787D02*
G03X362205I-3937J0D01*
G01Y600984D02*
G03X370079I3937J0D01*
G01X350394Y557480D02*
G03Y549606I0J-3937D01*
G01X325197D02*
G03Y557480I0J3937D01*
G01X352756Y577165D02*
G03X336221I-8267J0D01*
G01D02*
G03X352756I8268J0D01*
G01D02*
G03X336221I-8267J0D01*
G01D02*
G03X352756I8268J0D01*
G01D02*
G03X336221I-8267J0D01*
G01D02*
G03X352756I8268J0D01*
G01D02*
G03X336221I-8267J0D01*
G01D02*
G03X352756I8268J0D01*
G01X336221D02*
G03X352756I8268J0D01*
G01D02*
G03X336221I-8267J0D01*
G01D02*
G03X352756I8268J0D01*
G01D02*
G03X336221I-8267J0D01*
G01X362205Y561417D02*
Y615354D01*
G01X358268Y557480D02*
G03X362205Y561417I0J3937D01*
G01Y545669D02*
G03X358268Y549606I-3937J0D01*
G01X370079Y645472D02*
G03X362205I-3937J0D01*
G01Y670669D02*
G03X370079I3937J0D01*
G01X350394Y627165D02*
G03Y619291I0J-3937D01*
G01X325197D02*
G03Y627165I0J3937D01*
G01X352756Y646850D02*
G03X336221I-8267J0D01*
G01D02*
G03X352756I8268J0D01*
G01D02*
G03X336221I-8267J0D01*
G01D02*
G03X352756I8268J0D01*
G01D02*
G03X336221I-8267J0D01*
G01D02*
G03X352756I8268J0D01*
G01D02*
G03X336221I-8267J0D01*
G01D02*
G03X352756I8268J0D01*
G01X336221D02*
G03X352756I8268J0D01*
G01D02*
G03X336221I-8267J0D01*
G01D02*
G03X352756I8268J0D01*
G01D02*
G03X336221I-8267J0D01*
G01X362205Y631102D02*
Y685039D01*
G01X358268Y627165D02*
G03X362205Y631102I0J3937D01*
G01Y685039D02*
G03X358268Y688976I-3937J0D01*
G01X362205Y615354D02*
G03X358268Y619291I-3937J0D01*
G01X407087Y0D02*
G03Y-7874I0J-3937D01*
G01X381890D02*
G03Y0I0J3937D01*
G01X407087Y-7874D02*
X510237D01*
G01X396063Y19685D02*
G03X379528I-8268J0D01*
G01D02*
G03X396063I8267J0D01*
G01D02*
G03X379528I-8268J0D01*
G01D02*
G03X396063I8267J0D01*
G01D02*
G03X379528I-8268J0D01*
G01D02*
G03X396063I8267J0D01*
G01D02*
G03X379528I-8268J0D01*
G01D02*
G03X396063I8267J0D01*
G01X379528D02*
G03X396063I8267J0D01*
G01D02*
G03X379528I-8268J0D01*
G01D02*
G03X396063I8267J0D01*
G01D02*
G03X379528I-8268J0D01*
G01X374016Y0D02*
X543307D01*
G01X370079Y3937D02*
G03X374016Y0I3937J0D01*
G01X370079Y57874D02*
Y3937D01*
G01X407087Y69685D02*
G03Y61811I0J-3937D01*
G01X381890D02*
G03Y69685I0J3937D01*
G01X396063Y89370D02*
G03X379528I-8268J0D01*
G01D02*
G03X396063I8267J0D01*
G01D02*
G03X379528I-8268J0D01*
G01D02*
G03X396063I8267J0D01*
G01D02*
G03X379528I-8268J0D01*
G01D02*
G03X396063I8267J0D01*
G01D02*
G03X379528I-8268J0D01*
G01D02*
G03X396063I8267J0D01*
G01X379528D02*
G03X396063I8267J0D01*
G01D02*
G03X379528I-8268J0D01*
G01D02*
G03X396063I8267J0D01*
G01D02*
G03X379528I-8268J0D01*
G01X374016Y69685D02*
X543307D01*
G01X370079Y73622D02*
G03X374016Y69685I3937J0D01*
G01X370079Y127559D02*
Y73622D01*
G01X374016Y61811D02*
G03X370079Y57874I0J-3937D01*
G01X543307Y61811D02*
X374016D01*
G01X407087Y139370D02*
G03Y131496I0J-3937D01*
G01X381890D02*
G03Y139370I0J3937D01*
G01X396063Y159055D02*
G03X379528I-8268J0D01*
G01D02*
G03X396063I8267J0D01*
G01D02*
G03X379528I-8268J0D01*
G01D02*
G03X396063I8267J0D01*
G01D02*
G03X379528I-8268J0D01*
G01D02*
G03X396063I8267J0D01*
G01D02*
G03X379528I-8268J0D01*
G01D02*
G03X396063I8267J0D01*
G01X379528D02*
G03X396063I8267J0D01*
G01D02*
G03X379528I-8268J0D01*
G01D02*
G03X396063I8267J0D01*
G01D02*
G03X379528I-8268J0D01*
G01X374016Y139370D02*
X543307D01*
G01X370079Y143307D02*
G03X374016Y139370I3937J0D01*
G01X370079Y197244D02*
Y143307D01*
G01X374016Y131496D02*
G03X370079Y127559I0J-3937D01*
G01X543307Y131496D02*
X374016D01*
G01X407087Y278740D02*
G03Y270866I0J-3937D01*
G01X381890D02*
G03Y278740I0J3937D01*
G01X407087Y209055D02*
G03Y201181I0J-3937D01*
G01X381890D02*
G03Y209055I0J3937D01*
G01X374016Y278740D02*
X543307D01*
G01X370079Y282677D02*
G03X374016Y278740I3937J0D01*
G01X396063Y228740D02*
G03X379528I-8268J0D01*
G01D02*
G03X396063I8267J0D01*
G01D02*
G03X379528I-8268J0D01*
G01D02*
G03X396063I8267J0D01*
G01D02*
G03X379528I-8268J0D01*
G01D02*
G03X396063I8267J0D01*
G01D02*
G03X379528I-8268J0D01*
G01D02*
G03X396063I8267J0D01*
G01X379528D02*
G03X396063I8267J0D01*
G01D02*
G03X379528I-8268J0D01*
G01D02*
G03X396063I8267J0D01*
G01D02*
G03X379528I-8268J0D01*
G01X374016Y209055D02*
X543307D01*
G01X370079Y212992D02*
G03X374016Y209055I3937J0D01*
G01X370079Y266929D02*
Y212992D01*
G01X374016Y270866D02*
G03X370079Y266929I0J-3937D01*
G01X543307Y270866D02*
X374016D01*
G01Y201181D02*
G03X370079Y197244I0J-3937D01*
G01X543307Y201181D02*
X374016D01*
G01X407087Y348425D02*
G03Y340551I0J-3937D01*
G01X381890D02*
G03Y348425I0J3937D01*
G01X379528Y368110D02*
G03X396063I8267J0D01*
G01X379528D02*
G03X396063I8267J0D01*
G01X379528D02*
G03X396063I8267J0D01*
G01X379528D02*
G03X396063I8267J0D01*
G01X379528D02*
G03X396063I8267J0D01*
G01X379528D02*
G03X396063I8267J0D01*
G01X374016Y348425D02*
X543307D01*
G01X370079Y352362D02*
G03X374016Y348425I3937J0D01*
G01X370079Y406299D02*
Y352362D01*
G01X396063Y298425D02*
G03X379528I-8268J0D01*
G01D02*
G03X396063I8267J0D01*
G01D02*
G03X379528I-8268J0D01*
G01D02*
G03X396063I8267J0D01*
G01D02*
G03X379528I-8268J0D01*
G01D02*
G03X396063I8267J0D01*
G01D02*
G03X379528I-8268J0D01*
G01D02*
G03X396063I8267J0D01*
G01X379528D02*
G03X396063I8267J0D01*
G01D02*
G03X379528I-8268J0D01*
G01D02*
G03X396063I8267J0D01*
G01D02*
G03X379528I-8268J0D01*
G01X370079Y336614D02*
Y282677D01*
G01X374016Y340551D02*
G03X370079Y336614I0J-3937D01*
G01X543307Y340551D02*
X374016D01*
G01X407087Y418110D02*
G03Y410236I0J-3937D01*
G01X381890D02*
G03Y418110I0J3937D01*
G01X396063Y437795D02*
G03X379528I-8268J0D01*
G01D02*
G03X396063I8267J0D01*
G01D02*
G03X379528I-8268J0D01*
G01D02*
G03X396063I8267J0D01*
G01D02*
G03X379528I-8268J0D01*
G01D02*
G03X396063I8267J0D01*
G01D02*
G03X379528I-8268J0D01*
G01D02*
G03X396063I8267J0D01*
G01X379528D02*
G03X396063I8267J0D01*
G01D02*
G03X379528I-8268J0D01*
G01D02*
G03X396063I8267J0D01*
G01D02*
G03X379528I-8268J0D01*
G01X374016Y418110D02*
X543307D01*
G01X370079Y422047D02*
G03X374016Y418110I3937J0D01*
G01X370079Y475984D02*
Y422047D01*
G01X396063Y368110D02*
G03X379528I-8268J0D01*
G01X396063D02*
G03X379528I-8268J0D01*
G01X396063D02*
G03X379528I-8268J0D01*
G01X396063D02*
G03X379528I-8268J0D01*
G01X396063D02*
G03X379528I-8268J0D01*
G01X396063D02*
G03X379528I-8268J0D01*
G01X374016Y410236D02*
G03X370079Y406299I0J-3937D01*
G01X543307Y410236D02*
X374016D01*
G01X407087Y487795D02*
G03Y479921I0J-3937D01*
G01X381890D02*
G03Y487795I0J3937D01*
G01X396063Y507480D02*
G03X379528I-8268J0D01*
G01D02*
G03X396063I8267J0D01*
G01D02*
G03X379528I-8268J0D01*
G01D02*
G03X396063I8267J0D01*
G01D02*
G03X379528I-8268J0D01*
G01D02*
G03X396063I8267J0D01*
G01D02*
G03X379528I-8268J0D01*
G01D02*
G03X396063I8267J0D01*
G01X379528D02*
G03X396063I8267J0D01*
G01D02*
G03X379528I-8268J0D01*
G01D02*
G03X396063I8267J0D01*
G01D02*
G03X379528I-8268J0D01*
G01X374016Y487795D02*
X543307D01*
G01X370079Y491732D02*
G03X374016Y487795I3937J0D01*
G01X370079Y545669D02*
Y491732D01*
G01X374016Y479921D02*
G03X370079Y475984I0J-3937D01*
G01X543307Y479921D02*
X374016D01*
G01X407087Y557480D02*
G03Y549606I0J-3937D01*
G01X381890D02*
G03Y557480I0J3937D01*
G01X396063Y577165D02*
G03X379528I-8268J0D01*
G01D02*
G03X396063I8267J0D01*
G01D02*
G03X379528I-8268J0D01*
G01D02*
G03X396063I8267J0D01*
G01D02*
G03X379528I-8268J0D01*
G01D02*
G03X396063I8267J0D01*
G01D02*
G03X379528I-8268J0D01*
G01D02*
G03X396063I8267J0D01*
G01X379528D02*
G03X396063I8267J0D01*
G01D02*
G03X379528I-8268J0D01*
G01D02*
G03X396063I8267J0D01*
G01D02*
G03X379528I-8268J0D01*
G01X374016Y557480D02*
X543307D01*
G01X370079Y561417D02*
G03X374016Y557480I3937J0D01*
G01X370079Y615354D02*
Y561417D01*
G01X374016Y549606D02*
G03X370079Y545669I0J-3937D01*
G01X543307Y549606D02*
X374016D01*
G01X407087Y627165D02*
G03Y619291I0J-3937D01*
G01X381890D02*
G03Y627165I0J3937D01*
G01X396063Y646850D02*
G03X379528I-8268J0D01*
G01D02*
G03X396063I8267J0D01*
G01D02*
G03X379528I-8268J0D01*
G01D02*
G03X396063I8267J0D01*
G01D02*
G03X379528I-8268J0D01*
G01D02*
G03X396063I8267J0D01*
G01D02*
G03X379528I-8268J0D01*
G01D02*
G03X396063I8267J0D01*
G01X379528D02*
G03X396063I8267J0D01*
G01D02*
G03X379528I-8268J0D01*
G01D02*
G03X396063I8267J0D01*
G01D02*
G03X379528I-8268J0D01*
G01X374016Y627165D02*
X543307D01*
G01X370079Y631102D02*
G03X374016Y627165I3937J0D01*
G01X370079Y685039D02*
Y631102D01*
G01X374016Y688976D02*
G03X370079Y685039I0J-3937D01*
G01X543307Y688976D02*
X374016D01*
G01Y619291D02*
G03X370079Y615354I0J-3937D01*
G01X543307Y619291D02*
X374016D01*
G01X510237Y-7874D02*
G03Y0I0J3937D01*
G01X537796Y19685D02*
G03X521260I-8268J0D01*
G01D02*
G03X537796I8268J0D01*
G01D02*
G03X521260I-8268J0D01*
G01D02*
G03X537796I8268J0D01*
G01D02*
G03X521260I-8268J0D01*
G01D02*
G03X537796I8268J0D01*
G01D02*
G03X521260I-8268J0D01*
G01D02*
G03X537796I8268J0D01*
G01X521260D02*
G03X537796I8268J0D01*
G01D02*
G03X521260I-8268J0D01*
G01D02*
G03X537796I8268J0D01*
G01D02*
G03X521260I-8268J0D01*
G01X510237Y61811D02*
G03Y69685I0J3937D01*
G01X537796Y89370D02*
G03X521260I-8268J0D01*
G01D02*
G03X537796I8268J0D01*
G01D02*
G03X521260I-8268J0D01*
G01D02*
G03X537796I8268J0D01*
G01D02*
G03X521260I-8268J0D01*
G01D02*
G03X537796I8268J0D01*
G01D02*
G03X521260I-8268J0D01*
G01D02*
G03X537796I8268J0D01*
G01X521260D02*
G03X537796I8268J0D01*
G01D02*
G03X521260I-8268J0D01*
G01D02*
G03X537796I8268J0D01*
G01D02*
G03X521260I-8268J0D01*
G01X510237Y131496D02*
G03Y139370I0J3937D01*
G01X537796Y159055D02*
G03X521260I-8268J0D01*
G01D02*
G03X537796I8268J0D01*
G01D02*
G03X521260I-8268J0D01*
G01D02*
G03X537796I8268J0D01*
G01D02*
G03X521260I-8268J0D01*
G01D02*
G03X537796I8268J0D01*
G01D02*
G03X521260I-8268J0D01*
G01D02*
G03X537796I8268J0D01*
G01X521260D02*
G03X537796I8268J0D01*
G01D02*
G03X521260I-8268J0D01*
G01D02*
G03X537796I8268J0D01*
G01D02*
G03X521260I-8268J0D01*
G01X510237Y270866D02*
G03Y278740I0J3937D01*
G01Y201181D02*
G03Y209055I0J3937D01*
G01X537796Y228740D02*
G03X521260I-8268J0D01*
G01D02*
G03X537796I8268J0D01*
G01D02*
G03X521260I-8268J0D01*
G01D02*
G03X537796I8268J0D01*
G01D02*
G03X521260I-8268J0D01*
G01D02*
G03X537796I8268J0D01*
G01D02*
G03X521260I-8268J0D01*
G01D02*
G03X537796I8268J0D01*
G01X521260D02*
G03X537796I8268J0D01*
G01D02*
G03X521260I-8268J0D01*
G01D02*
G03X537796I8268J0D01*
G01D02*
G03X521260I-8268J0D01*
G01X510237Y340551D02*
G03Y348425I0J3937D01*
G01X521260Y368110D02*
G03X537796I8268J0D01*
G01X521260D02*
G03X537796I8268J0D01*
G01X521260D02*
G03X537796I8268J0D01*
G01X521260D02*
G03X537796I8268J0D01*
G01X521260D02*
G03X537796I8268J0D01*
G01X521260D02*
G03X537796I8268J0D01*
G01Y298425D02*
G03X521260I-8268J0D01*
G01D02*
G03X537796I8268J0D01*
G01D02*
G03X521260I-8268J0D01*
G01D02*
G03X537796I8268J0D01*
G01D02*
G03X521260I-8268J0D01*
G01D02*
G03X537796I8268J0D01*
G01D02*
G03X521260I-8268J0D01*
G01D02*
G03X537796I8268J0D01*
G01X521260D02*
G03X537796I8268J0D01*
G01D02*
G03X521260I-8268J0D01*
G01D02*
G03X537796I8268J0D01*
G01D02*
G03X521260I-8268J0D01*
G01X510237Y410236D02*
G03Y418110I0J3937D01*
G01X537796Y437795D02*
G03X521260I-8268J0D01*
G01D02*
G03X537796I8268J0D01*
G01D02*
G03X521260I-8268J0D01*
G01D02*
G03X537796I8268J0D01*
G01D02*
G03X521260I-8268J0D01*
G01D02*
G03X537796I8268J0D01*
G01D02*
G03X521260I-8268J0D01*
G01D02*
G03X537796I8268J0D01*
G01X521260D02*
G03X537796I8268J0D01*
G01D02*
G03X521260I-8268J0D01*
G01D02*
G03X537796I8268J0D01*
G01D02*
G03X521260I-8268J0D01*
G01X537796Y368110D02*
G03X521260I-8268J0D01*
G01X537796D02*
G03X521260I-8268J0D01*
G01X537796D02*
G03X521260I-8268J0D01*
G01X537796D02*
G03X521260I-8268J0D01*
G01X537796D02*
G03X521260I-8268J0D01*
G01X537796D02*
G03X521260I-8268J0D01*
G01X510237Y479921D02*
G03Y487795I0J3937D01*
G01X537796Y507480D02*
G03X521260I-8268J0D01*
G01D02*
G03X537796I8268J0D01*
G01D02*
G03X521260I-8268J0D01*
G01D02*
G03X537796I8268J0D01*
G01D02*
G03X521260I-8268J0D01*
G01D02*
G03X537796I8268J0D01*
G01D02*
G03X521260I-8268J0D01*
G01D02*
G03X537796I8268J0D01*
G01X521260D02*
G03X537796I8268J0D01*
G01D02*
G03X521260I-8268J0D01*
G01D02*
G03X537796I8268J0D01*
G01D02*
G03X521260I-8268J0D01*
G01X510237Y549606D02*
G03Y557480I0J3937D01*
G01X537796Y577165D02*
G03X521260I-8268J0D01*
G01D02*
G03X537796I8268J0D01*
G01D02*
G03X521260I-8268J0D01*
G01D02*
G03X537796I8268J0D01*
G01D02*
G03X521260I-8268J0D01*
G01D02*
G03X537796I8268J0D01*
G01D02*
G03X521260I-8268J0D01*
G01D02*
G03X537796I8268J0D01*
G01X521260D02*
G03X537796I8268J0D01*
G01D02*
G03X521260I-8268J0D01*
G01D02*
G03X537796I8268J0D01*
G01D02*
G03X521260I-8268J0D01*
G01X510237Y619291D02*
G03Y627165I0J3937D01*
G01X537796Y646850D02*
G03X521260I-8268J0D01*
G01D02*
G03X537796I8268J0D01*
G01D02*
G03X521260I-8268J0D01*
G01D02*
G03X537796I8268J0D01*
G01D02*
G03X521260I-8268J0D01*
G01D02*
G03X537796I8268J0D01*
G01D02*
G03X521260I-8268J0D01*
G01D02*
G03X537796I8268J0D01*
G01X521260D02*
G03X537796I8268J0D01*
G01D02*
G03X521260I-8268J0D01*
G01D02*
G03X537796I8268J0D01*
G01D02*
G03X521260I-8268J0D01*
G01X539370Y-19685D02*
G03X547244Y-11811I0J7874D01*
G01X535433Y0D02*
G03Y-7874I0J-3937D01*
G01X547244D02*
Y-11811D01*
G01X535433Y-7874D02*
X547244D01*
G01Y3937D02*
Y57874D01*
G01X543307Y0D02*
G03X547244Y3937I0J3937D01*
G01X535433Y69685D02*
G03Y61811I0J-3937D01*
G01X547244Y73622D02*
Y127559D01*
G01X543307Y69685D02*
G03X547244Y73622I0J3937D01*
G01Y57874D02*
G03X543307Y61811I-3937J0D01*
G01X535433Y139370D02*
G03Y131496I0J-3937D01*
G01X547244Y143307D02*
Y197244D01*
G01X543307Y139370D02*
G03X547244Y143307I0J3937D01*
G01Y127559D02*
G03X543307Y131496I-3937J0D01*
G01X535433Y278740D02*
G03Y270866I0J-3937D01*
G01Y209055D02*
G03Y201181I0J-3937D01*
G01X543307Y278740D02*
G03X547244Y282677I0J3937D01*
G01Y212992D02*
Y266929D01*
G01X543307Y209055D02*
G03X547244Y212992I0J3937D01*
G01Y266929D02*
G03X543307Y270866I-3937J0D01*
G01X547244Y197244D02*
G03X543307Y201181I-3937J0D01*
G01X535433Y348425D02*
G03Y340551I0J-3937D01*
G01X547244Y352362D02*
Y406299D01*
G01X543307Y348425D02*
G03X547244Y352362I0J3937D01*
G01Y282677D02*
Y336614D01*
G01D02*
G03X543307Y340551I-3937J0D01*
G01X535433Y418110D02*
G03Y410236I0J-3937D01*
G01X547244Y422047D02*
Y475984D01*
G01X543307Y418110D02*
G03X547244Y422047I0J3937D01*
G01Y406299D02*
G03X543307Y410236I-3937J0D01*
G01X535433Y487795D02*
G03Y479921I0J-3937D01*
G01X547244Y491732D02*
Y545669D01*
G01X543307Y487795D02*
G03X547244Y491732I0J3937D01*
G01Y475984D02*
G03X543307Y479921I-3937J0D01*
G01X535433Y557480D02*
G03Y549606I0J-3937D01*
G01X547244Y561417D02*
Y615354D01*
G01X543307Y557480D02*
G03X547244Y561417I0J3937D01*
G01Y545669D02*
G03X543307Y549606I-3937J0D01*
G01X535433Y627165D02*
G03Y619291I0J-3937D01*
G01X547244Y631102D02*
Y685039D01*
G01X543307Y627165D02*
G03X547244Y631102I0J3937D01*
G01Y685039D02*
G03X543307Y688976I-3937J0D01*
G01X547244Y615354D02*
G03X543307Y619291I-3937J0D01*
G54D12*
G01X34200Y47000D02*
X32796Y45596D01*
G01D02*
Y43681D01*
G01X28100Y39300D02*
X28800D01*
G01D02*
X30827Y41327D01*
G01D02*
Y43681D01*
G01X111800Y52264D02*
X105603Y58461D01*
G01D02*
X45361D01*
G01D02*
X44078Y57178D01*
G01X42638Y43681D02*
Y46262D01*
G01D02*
X40670Y48230D01*
G01D02*
Y50217D01*
G01X56000Y55500D02*
X92000D01*
G01D02*
X99000Y48500D01*
G01D02*
Y46500D01*
G01X103700Y36400D02*
X99000Y41100D01*
G01D02*
Y46500D01*
G01X39400Y46831D02*
X38701Y46132D01*
G01D02*
Y43681D01*
G01X44607Y50217D02*
Y46831D01*
G01X52218Y47067D02*
X52481Y47330D01*
G01D02*
Y50217D01*
G01X47200Y47067D02*
X48544Y48411D01*
G01D02*
Y50217D01*
G01X36733D02*
Y47067D01*
G01X49730Y46821D02*
X50512Y46039D01*
G01D02*
Y43681D01*
M02*
